FILE_TYPE = MACRO_DRAWING;
SET COLOR_WIRE YELLOW;
SET COLOR_PROP ORANGE;
SET COLOR_DOT WHITE;
SET COLOR_ARC YELLOW;
SET COLOR_BODY GREEN;
SET COLOR_NOTE PURPLE;
SET PROP_DISPLAY VALUE;
SET PAGE_NUMBER P401;
FORCEADD PT5161LRS..3
(-4375 2450);
FORCEPROP 1 LAST LOCATION U6014
J 0
(-4875 4075);
DISPLAY 0.723404 (-4875 4075);
PAINT GREEN (-4875 4075);
FORCEPROP 0 LAST $SEC 3
J 0
(-4875 4225);
DISPLAY 0.680851 (-4875 4225);
PAINT MONO (-4875 4225);
DISPLAY INVISIBLE (-4875 4225);
FORCEPROP 0 LAST CDS_SEC 3
J 0
(-4875 4225);
DISPLAY 0.680851 (-4875 4225);
DISPLAY INVISIBLE (-4875 4225);
FORCEPROP 0 LASTPIN (-3775 2400) $PN G35
J 0
(-3765 2410);
DISPLAY 0.680851 (-3765 2410);
PAINT MONO (-3765 2410);
FORCEPROP 0 LASTPIN (-5025 1750) $PN FF5
J 2
(-5035 1760);
DISPLAY 0.680851 (-5035 1760);
PAINT MONO (-5035 1760);
FORCEPROP 0 LASTPIN (-5025 1650) $PN FJ3
J 2
(-5035 1660);
DISPLAY 0.680851 (-5035 1660);
PAINT MONO (-5035 1660);
FORCEPROP 0 LASTPIN (-5025 3650) $PN FJ6
J 2
(-5035 3660);
DISPLAY 0.680851 (-5035 3660);
PAINT MONO (-5035 3660);
FORCEPROP 0 LASTPIN (-5025 3550) $PN FJ23
J 2
(-5035 3560);
DISPLAY 0.680851 (-5035 3560);
PAINT MONO (-5035 3560);
FORCEPROP 0 LASTPIN (-5025 3450) $PN FJ25
J 2
(-5035 3460);
DISPLAY 0.680851 (-5035 3460);
PAINT MONO (-5035 3460);
FORCEPROP 0 LASTPIN (-5025 3350) $PN FJ28
J 2
(-5035 3360);
DISPLAY 0.680851 (-5035 3360);
PAINT MONO (-5035 3360);
FORCEPROP 0 LASTPIN (-3775 2000) $PN FJ31
J 0
(-3765 2010);
DISPLAY 0.680851 (-3765 2010);
PAINT MONO (-3765 2010);
FORCEPROP 0 LASTPIN (-3775 3750) $PN B3
J 0
(-3765 3760);
DISPLAY 0.680851 (-3765 3760);
PAINT MONO (-3765 3760);
FORCEPROP 0 LASTPIN (-3775 3450) $PN B6
J 0
(-3765 3460);
DISPLAY 0.680851 (-3765 3460);
PAINT MONO (-3765 3460);
FORCEPROP 0 LASTPIN (-3775 3650) $PN B9
J 0
(-3765 3660);
DISPLAY 0.680851 (-3765 3660);
PAINT MONO (-3765 3660);
FORCEPROP 0 LASTPIN (-3775 3200) $PN FF8
J 0
(-3765 3210);
DISPLAY 0.680851 (-3765 3210);
PAINT MONO (-3765 3210);
FORCEPROP 0 LASTPIN (-3775 3550) $PN B12
J 0
(-3765 3560);
DISPLAY 0.680851 (-3765 3560);
PAINT MONO (-3765 3560);
FORCEPROP 0 LASTPIN (-3775 3350) $PN E8
J 0
(-3765 3360);
DISPLAY 0.680851 (-3765 3360);
PAINT MONO (-3765 3360);
FORCEPROP 0 LASTPIN (-3775 2900) $PN FJ9
J 0
(-3765 2910);
DISPLAY 0.680851 (-3765 2910);
PAINT MONO (-3765 2910);
FORCEPROP 0 LASTPIN (-3775 2300) $PN F2
J 0
(-3765 2310);
DISPLAY 0.680851 (-3765 2310);
PAINT MONO (-3765 2310);
FORCEPROP 0 LASTPIN (-3775 1150) $PN E18
J 0
(-3765 1160);
DISPLAY 0.680851 (-3765 1160);
PAINT MONO (-3765 1160);
FORCEPROP 0 LASTPIN (-3775 1300) $PN B16
J 0
(-3765 1310);
DISPLAY 0.680851 (-3765 1310);
PAINT MONO (-3765 1310);
FORCEPROP 0 LASTPIN (-5025 1150) $PN FF18
J 2
(-5035 1160);
DISPLAY 0.680851 (-5035 1160);
PAINT MONO (-5035 1160);
FORCEPROP 0 LASTPIN (-5025 1300) $PN FJ16
J 2
(-5035 1310);
DISPLAY 0.680851 (-5035 1310);
PAINT MONO (-5035 1310);
FORCEPROP 0 LASTPIN (-3775 2200) $PN FF11
J 0
(-3765 2210);
DISPLAY 0.680851 (-3765 2210);
PAINT MONO (-3765 2210);
FORCEPROP 0 LASTPIN (-3775 2800) $PN E11
J 0
(-3765 2810);
DISPLAY 0.680851 (-3765 2810);
PAINT MONO (-3765 2810);
FORCEPROP 0 LASTPIN (-3775 2700) $PN FF33
J 0
(-3765 2710);
DISPLAY 0.680851 (-3765 2710);
PAINT MONO (-3765 2710);
FORCEPROP 0 LASTPIN (-5025 2750) $PN F34
J 2
(-5035 2760);
DISPLAY 0.680851 (-5035 2760);
PAINT MONO (-5035 2760);
FORCEPROP 0 LASTPIN (-5025 2650) $PN B23
J 2
(-5035 2660);
DISPLAY 0.680851 (-5035 2660);
PAINT MONO (-5035 2660);
FORCEPROP 0 LASTPIN (-5025 2550) $PN B25
J 2
(-5035 2560);
DISPLAY 0.680851 (-5035 2560);
PAINT MONO (-5035 2560);
FORCEPROP 0 LASTPIN (-5025 3000) $PN B31
J 2
(-5035 3010);
DISPLAY 0.680851 (-5035 3010);
PAINT MONO (-5035 3010);
FORCEPROP 0 LASTPIN (-5025 2900) $PN B28
J 2
(-5035 2910);
DISPLAY 0.680851 (-5035 2910);
PAINT MONO (-5035 2910);
FORCEPROP 0 LASTPIN (-3775 1800) $PN E30
J 0
(-3765 1810);
DISPLAY 0.680851 (-3765 1810);
PAINT MONO (-3765 1810);
FORCEPROP 0 LASTPIN (-5025 2250) $PN FF24
J 2
(-5035 2260);
DISPLAY 0.680851 (-5035 2260);
PAINT MONO (-5035 2260);
FORCEPROP 0 LASTPIN (-5025 2150) $PN FF27
J 2
(-5035 2160);
DISPLAY 0.680851 (-5035 2160);
PAINT MONO (-5035 2160);
FORCEPROP 0 LASTPIN (-5025 2050) $PN FF30
J 2
(-5035 2060);
DISPLAY 0.680851 (-5035 2060);
PAINT MONO (-5035 2060);
FORCEPROP 2 LAST PART_TYPE SMLF
J 0
(-4875 4175);
DISPLAY 0.680851 (-4875 4175);
FORCEPROP 2 LAST VALUE PT5161LRS
J 0
(-4875 4125);
DISPLAY 0.680851 (-4875 4125);
FORCEPROP 1 LAST MATERIAL IC
J 0
(-4875 3925);
DISPLAY 0.723404 (-4875 3925);
PAINT GREEN (-4875 3925);
FORCEPROP 1 LAST NEEDS_NO_SIZE TRUE
J 0
(-4375 2450);
DISPLAY 0.723404 (-4375 2450);
PAINT GREEN (-4375 2450);
DISPLAY INVISIBLE (-4375 2450);
FORCEPROP 1 LAST CDS_LMAN_SYM_OUTLINE -500,1450,450,-1400
J 0
(-4375 2450);
DISPLAY 0.468085 (-4375 2450);
PAINT GREEN (-4375 2450);
DISPLAY INVISIBLE (-4375 2450);
FORCEPROP 2 LAST CDS_LIB pure_quanta
J 0
(-4375 2450);
DISPLAY INVISIBLE (-4375 2450);
FORCEPROP 1 LAST PATH I1
J 0
(-4375 2450);
DISPLAY 0.723404 (-4375 2450);
PAINT GREEN (-4375 2450);
DISPLAY INVISIBLE (-4375 2450);
FORCEPROP 1 LAST PART_NUMBER AJ051610U03
J 0
(-4875 4000);
DISPLAY 0.723404 (-4875 4000);
PAINT GREEN (-4875 4000);
DISPLAY INVISIBLE (-4875 4000);
FORCEADD P1V0..1
(-1475 6400);
FORCEPROP 3 LASTPIN (-1475 6350) SIG_NAME P1V8_CPU1_RT_1D\g
J 0
(-1465 6360);
DISPLAY 0.659574 (-1465 6360);
PAINT MONO (-1465 6360);
DISPLAY INVISIBLE (-1465 6360);
FORCEPROP 1 LAST HDL_POWER P1V8_CPU1_RT_1D
J 1
(-1475 6450);
DISPLAY 0.489362 (-1475 6450);
PAINT SKYBLUE (-1475 6450);
FORCEPROP 2 LAST CDS_LIB pure_quanta_power
J 0
(-1475 6400);
DISPLAY INVISIBLE (-1475 6400);
FORCEPROP 1 LAST PATH I100
J 0
(-1425 6425);
DISPLAY 0.872340 (-1425 6425);
PAINT AQUA (-1425 6425);
DISPLAY INVISIBLE (-1425 6425);
FORCEADD Q_RES..2
R 2
(-1475 6150);
FORCEPROP 1 LAST LOCATION R6724
J 2
(-1520 6275);
DISPLAY 0.787234 (-1520 6275);
FORCEPROP 0 LAST $SEC 1
J 0
(-1500 6325);
DISPLAY 0.680851 (-1500 6325);
PAINT MONO (-1500 6325);
DISPLAY INVISIBLE (-1500 6325);
FORCEPROP 0 LAST CDS_SEC 1
J 0
(-1500 6325);
DISPLAY 0.680851 (-1500 6325);
DISPLAY INVISIBLE (-1500 6325);
FORCEPROP 1 LASTPIN (-1475 6250) $PN 1
J 2
(-1480 6212);
DISPLAY 0.787234 (-1480 6212);
PAINT MONO (-1480 6212);
FORCEPROP 1 LASTPIN (-1475 6050) $PN 2
J 2
(-1480 6060);
DISPLAY 0.787234 (-1480 6060);
PAINT MONO (-1480 6060);
FORCEPROP 1 LAST VALUE 4.7K
J 2
(-1520 6225);
DISPLAY 0.787234 (-1520 6225);
FORCEPROP 1 LAST TOLERANCE 5%
J 2
(-1520 6175);
DISPLAY 0.787234 (-1520 6175);
FORCEPROP 1 LAST WATTAGE 1/20W
J 2
(-1515 6125);
DISPLAY 0.787234 (-1515 6125);
FORCEPROP 1 LAST MATERIAL EMPTY
J 2
(-1515 6075);
DISPLAY 0.787234 (-1515 6075);
FORCEPROP 1 LAST PACK_TYPE 0201LF
J 2
(-1525 6000);
DISPLAY 0.787234 (-1525 6000);
FORCEPROP 2 LAST CDS_LIB pure_quanta
J 2
(-1475 6150);
DISPLAY INVISIBLE (-1475 6150);
FORCEPROP 1 LAST PATH I101
J 2
(-1525 6325);
DISPLAY 0.978723 (-1525 6325);
PAINT WHITE (-1525 6325);
DISPLAY INVISIBLE (-1525 6325);
FORCEPROP 1 LAST PART_NUMBER CS24701JE04
J 2
(-1515 6025);
DISPLAY 0.978723 (-1515 6025);
DISPLAY INVISIBLE (-1515 6025);
FORCEADD Q_RES..2
(-3475 6100);
FORCEPROP 1 LAST LOCATION R6712
J 0
(-3430 6225);
DISPLAY 0.787234 (-3430 6225);
FORCEPROP 0 LAST $SEC 1
J 0
(-3425 6275);
DISPLAY 0.680851 (-3425 6275);
PAINT MONO (-3425 6275);
DISPLAY INVISIBLE (-3425 6275);
FORCEPROP 0 LAST CDS_SEC 1
J 0
(-3425 6275);
DISPLAY 0.680851 (-3425 6275);
DISPLAY INVISIBLE (-3425 6275);
FORCEPROP 1 LASTPIN (-3475 6200) $PN 1
J 0
(-3470 6162);
DISPLAY 0.787234 (-3470 6162);
PAINT MONO (-3470 6162);
FORCEPROP 1 LASTPIN (-3475 6000) $PN 2
J 0
(-3470 6010);
DISPLAY 0.787234 (-3470 6010);
PAINT MONO (-3470 6010);
FORCEPROP 1 LAST PACK_TYPE 0201LF
J 0
(-3435 5925);
DISPLAY 0.787234 (-3435 5925);
FORCEPROP 1 LAST MATERIAL CHIP
J 0
(-3435 6025);
DISPLAY 0.787234 (-3435 6025);
FORCEPROP 1 LAST TOLERANCE 1%
J 0
(-3430 6125);
DISPLAY 0.787234 (-3430 6125);
FORCEPROP 1 LAST WATTAGE 1/20W
J 0
(-3435 6075);
DISPLAY 0.787234 (-3435 6075);
FORCEPROP 1 LAST VALUE 1K
J 0
(-3430 6175);
DISPLAY 0.787234 (-3430 6175);
FORCEPROP 2 LAST CDS_LIB pure_quanta
J 0
(-3475 6100);
DISPLAY INVISIBLE (-3475 6100);
FORCEPROP 1 LAST PATH I102
J 0
(-3425 6275);
DISPLAY 0.978723 (-3425 6275);
PAINT WHITE (-3425 6275);
DISPLAY INVISIBLE (-3425 6275);
FORCEPROP 1 LAST PART_NUMBER CS21001FE07
J 0
(-3435 5975);
DISPLAY 0.978723 (-3435 5975);
DISPLAY INVISIBLE (-3435 5975);
FORCEADD Q_RES..2
(-3475 5325);
FORCEPROP 1 LAST LOCATION R6713
J 0
(-3430 5450);
DISPLAY 0.787234 (-3430 5450);
FORCEPROP 0 LAST $SEC 1
J 0
(-3425 5500);
DISPLAY 0.680851 (-3425 5500);
PAINT MONO (-3425 5500);
DISPLAY INVISIBLE (-3425 5500);
FORCEPROP 0 LAST CDS_SEC 1
J 0
(-3425 5500);
DISPLAY 0.680851 (-3425 5500);
DISPLAY INVISIBLE (-3425 5500);
FORCEPROP 1 LASTPIN (-3475 5425) $PN 1
J 0
(-3470 5387);
DISPLAY 0.787234 (-3470 5387);
PAINT MONO (-3470 5387);
FORCEPROP 1 LASTPIN (-3475 5225) $PN 2
J 0
(-3470 5235);
DISPLAY 0.787234 (-3470 5235);
PAINT MONO (-3470 5235);
FORCEPROP 1 LAST PACK_TYPE 0201LF
J 0
(-3435 5150);
DISPLAY 0.787234 (-3435 5150);
FORCEPROP 1 LAST VALUE 1K
J 0
(-3430 5400);
DISPLAY 0.787234 (-3430 5400);
FORCEPROP 1 LAST TOLERANCE 1%
J 0
(-3430 5350);
DISPLAY 0.787234 (-3430 5350);
FORCEPROP 1 LAST MATERIAL EMPTY
J 0
(-3435 5250);
DISPLAY 0.787234 (-3435 5250);
FORCEPROP 1 LAST WATTAGE 1/20W
J 0
(-3435 5300);
DISPLAY 0.787234 (-3435 5300);
FORCEPROP 2 LAST CDS_LIB pure_quanta
J 0
(-3475 5325);
DISPLAY INVISIBLE (-3475 5325);
FORCEPROP 1 LAST PATH I103
J 0
(-3425 5500);
DISPLAY 0.978723 (-3425 5500);
PAINT WHITE (-3425 5500);
DISPLAY INVISIBLE (-3425 5500);
FORCEPROP 1 LAST PART_NUMBER CS21001FE07
J 0
(-3435 5200);
DISPLAY 0.978723 (-3435 5200);
DISPLAY INVISIBLE (-3435 5200);
FORCEADD Q_RES..2
(-3175 6100);
FORCEPROP 1 LAST LOCATION R6714
J 0
(-3130 6225);
DISPLAY 0.978723 (-3130 6225);
FORCEPROP 0 LAST $SEC 1
J 0
(-3125 6275);
DISPLAY 0.680851 (-3125 6275);
PAINT MONO (-3125 6275);
DISPLAY INVISIBLE (-3125 6275);
FORCEPROP 0 LAST CDS_SEC 1
J 0
(-3125 6275);
DISPLAY 0.680851 (-3125 6275);
DISPLAY INVISIBLE (-3125 6275);
FORCEPROP 1 LASTPIN (-3175 6200) $PN 1
J 0
(-3170 6162);
DISPLAY 0.787234 (-3170 6162);
PAINT MONO (-3170 6162);
FORCEPROP 1 LASTPIN (-3175 6000) $PN 2
J 0
(-3170 6010);
DISPLAY 0.787234 (-3170 6010);
PAINT MONO (-3170 6010);
FORCEPROP 1 LAST PACK_TYPE 0201LF
J 0
(-3135 5925);
DISPLAY 0.787234 (-3135 5925);
FORCEPROP 1 LAST VALUE 1K
J 0
(-3130 6175);
DISPLAY 0.787234 (-3130 6175);
FORCEPROP 1 LAST WATTAGE 1/20W
J 0
(-3135 6075);
DISPLAY 0.787234 (-3135 6075);
FORCEPROP 1 LAST MATERIAL EMPTY
J 0
(-3135 6025);
DISPLAY 0.787234 (-3135 6025);
FORCEPROP 1 LAST TOLERANCE 1%
J 0
(-3130 6125);
DISPLAY 0.787234 (-3130 6125);
FORCEPROP 2 LAST CDS_LIB pure_quanta
J 0
(-3175 6100);
DISPLAY INVISIBLE (-3175 6100);
FORCEPROP 1 LAST PATH I104
J 0
(-3125 6275);
DISPLAY 0.978723 (-3125 6275);
PAINT WHITE (-3125 6275);
DISPLAY INVISIBLE (-3125 6275);
FORCEPROP 1 LAST PART_NUMBER CS21001FE07
J 0
(-3135 5975);
DISPLAY 0.978723 (-3135 5975);
DISPLAY INVISIBLE (-3135 5975);
FORCEADD Q_RES..2
(-3175 5325);
FORCEPROP 1 LAST LOCATION R6715
J 0
(-3130 5450);
DISPLAY 0.787234 (-3130 5450);
FORCEPROP 0 LAST $SEC 1
J 0
(-3125 5500);
DISPLAY 0.680851 (-3125 5500);
PAINT MONO (-3125 5500);
DISPLAY INVISIBLE (-3125 5500);
FORCEPROP 0 LAST CDS_SEC 1
J 0
(-3125 5500);
DISPLAY 0.680851 (-3125 5500);
DISPLAY INVISIBLE (-3125 5500);
FORCEPROP 1 LASTPIN (-3175 5425) $PN 1
J 0
(-3170 5387);
DISPLAY 0.787234 (-3170 5387);
PAINT MONO (-3170 5387);
FORCEPROP 1 LASTPIN (-3175 5225) $PN 2
J 0
(-3170 5235);
DISPLAY 0.787234 (-3170 5235);
PAINT MONO (-3170 5235);
FORCEPROP 1 LAST MATERIAL CHIP
J 0
(-3135 5250);
DISPLAY 0.787234 (-3135 5250);
FORCEPROP 1 LAST VALUE 20K
J 0
(-3130 5400);
DISPLAY 0.787234 (-3130 5400);
FORCEPROP 1 LAST TOLERANCE 1%
J 0
(-3130 5350);
DISPLAY 0.787234 (-3130 5350);
FORCEPROP 1 LAST WATTAGE 1/20W
J 0
(-3135 5300);
DISPLAY 0.787234 (-3135 5300);
FORCEPROP 1 LAST PACK_TYPE 0201LF
J 0
(-3135 5150);
DISPLAY 0.787234 (-3135 5150);
FORCEPROP 2 LAST CDS_LIB pure_quanta
J 0
(-3175 5325);
DISPLAY INVISIBLE (-3175 5325);
FORCEPROP 1 LAST PATH I105
J 0
(-3125 5500);
DISPLAY 0.978723 (-3125 5500);
PAINT WHITE (-3125 5500);
DISPLAY INVISIBLE (-3125 5500);
FORCEPROP 1 LAST PART_NUMBER CS32001FE00
J 0
(-3135 5200);
DISPLAY 0.978723 (-3135 5200);
DISPLAY INVISIBLE (-3135 5200);
FORCEADD Q_RES..2
(-2825 5325);
FORCEPROP 1 LAST LOCATION R6717
J 0
(-2780 5450);
DISPLAY 0.978723 (-2780 5450);
FORCEPROP 0 LAST $SEC 1
J 0
(-2775 5500);
DISPLAY 0.680851 (-2775 5500);
PAINT MONO (-2775 5500);
DISPLAY INVISIBLE (-2775 5500);
FORCEPROP 0 LAST CDS_SEC 1
J 0
(-2775 5500);
DISPLAY 0.680851 (-2775 5500);
DISPLAY INVISIBLE (-2775 5500);
FORCEPROP 1 LASTPIN (-2825 5425) $PN 1
J 0
(-2820 5387);
DISPLAY 0.787234 (-2820 5387);
PAINT MONO (-2820 5387);
FORCEPROP 1 LASTPIN (-2825 5225) $PN 2
J 0
(-2820 5235);
DISPLAY 0.787234 (-2820 5235);
PAINT MONO (-2820 5235);
FORCEPROP 1 LAST VALUE 1K
J 0
(-2780 5400);
DISPLAY 0.787234 (-2780 5400);
FORCEPROP 1 LAST TOLERANCE 1%
J 0
(-2780 5350);
DISPLAY 0.787234 (-2780 5350);
FORCEPROP 1 LAST MATERIAL CHIP
J 0
(-2785 5250);
DISPLAY 0.787234 (-2785 5250);
FORCEPROP 1 LAST WATTAGE 1/20W
J 0
(-2785 5300);
DISPLAY 0.787234 (-2785 5300);
FORCEPROP 1 LAST PACK_TYPE 0201LF
J 0
(-2785 5150);
DISPLAY 0.787234 (-2785 5150);
FORCEPROP 2 LAST CDS_LIB pure_quanta
J 0
(-2825 5325);
DISPLAY INVISIBLE (-2825 5325);
FORCEPROP 1 LAST PATH I106
J 0
(-2775 5500);
DISPLAY 0.978723 (-2775 5500);
PAINT WHITE (-2775 5500);
DISPLAY INVISIBLE (-2775 5500);
FORCEPROP 1 LAST PART_NUMBER CS21001FE07
J 0
(-2785 5200);
DISPLAY 0.978723 (-2785 5200);
DISPLAY INVISIBLE (-2785 5200);
FORCEADD Q_RES..2
(-2825 6075);
FORCEPROP 1 LAST LOCATION R6716
J 0
(-2780 6200);
DISPLAY 0.978723 (-2780 6200);
FORCEPROP 0 LAST $SEC 1
J 0
(-2775 6250);
DISPLAY 0.680851 (-2775 6250);
PAINT MONO (-2775 6250);
DISPLAY INVISIBLE (-2775 6250);
FORCEPROP 0 LAST CDS_SEC 1
J 0
(-2775 6250);
DISPLAY 0.680851 (-2775 6250);
DISPLAY INVISIBLE (-2775 6250);
FORCEPROP 1 LASTPIN (-2825 6175) $PN 1
J 0
(-2820 6137);
DISPLAY 0.787234 (-2820 6137);
PAINT MONO (-2820 6137);
FORCEPROP 1 LASTPIN (-2825 5975) $PN 2
J 0
(-2820 5985);
DISPLAY 0.787234 (-2820 5985);
PAINT MONO (-2820 5985);
FORCEPROP 1 LAST MATERIAL EMPTY
J 0
(-2785 6000);
DISPLAY 0.787234 (-2785 6000);
FORCEPROP 1 LAST PACK_TYPE 0201LF
J 0
(-2785 5900);
DISPLAY 0.787234 (-2785 5900);
FORCEPROP 1 LAST TOLERANCE 1%
J 0
(-2780 6100);
DISPLAY 0.787234 (-2780 6100);
FORCEPROP 1 LAST WATTAGE 1/20W
J 0
(-2785 6050);
DISPLAY 0.787234 (-2785 6050);
FORCEPROP 1 LAST VALUE 1K
J 0
(-2780 6150);
DISPLAY 0.787234 (-2780 6150);
FORCEPROP 2 LAST CDS_LIB pure_quanta
J 0
(-2825 6075);
DISPLAY INVISIBLE (-2825 6075);
FORCEPROP 1 LAST PATH I107
J 0
(-2775 6250);
DISPLAY 0.978723 (-2775 6250);
PAINT WHITE (-2775 6250);
DISPLAY INVISIBLE (-2775 6250);
FORCEPROP 1 LAST PART_NUMBER CS21001FE07
J 0
(-2785 5950);
DISPLAY 0.978723 (-2785 5950);
DISPLAY INVISIBLE (-2785 5950);
FORCEADD Q_RES..1
(-2675 2400);
FORCEPROP 1 LAST LOCATION R1387
J 0
(-2725 2450);
DISPLAY 0.978723 (-2725 2450);
FORCEPROP 0 LAST $SEC 1
J 0
(-2725 2500);
DISPLAY 0.680851 (-2725 2500);
PAINT MONO (-2725 2500);
DISPLAY INVISIBLE (-2725 2500);
FORCEPROP 0 LAST CDS_SEC 1
J 0
(-2725 2500);
DISPLAY 0.680851 (-2725 2500);
DISPLAY INVISIBLE (-2725 2500);
FORCEPROP 1 LASTPIN (-2775 2400) $PN 1
J 0
(-2763 2412);
DISPLAY 0.787234 (-2763 2412);
PAINT MONO (-2763 2412);
FORCEPROP 1 LASTPIN (-2575 2400) $PN 2
J 0
(-2613 2412);
DISPLAY 0.787234 (-2613 2412);
PAINT MONO (-2613 2412);
FORCEPROP 1 LAST VALUE 4.7K
J 2
(-2425 2400);
DISPLAY 0.638298 (-2425 2400);
FORCEPROP 1 LAST PACK_TYPE 0201LF
J 0
(-2250 2400);
DISPLAY 0.638298 (-2250 2400);
FORCEPROP 1 LAST MATERIAL CHIP
J 0
(-2400 2400);
DISPLAY 0.638298 (-2400 2400);
FORCEPROP 1 LAST WATTAGE 1/20W
J 2
(-2700 2250);
DISPLAY 0.978723 (-2700 2250);
DISPLAY INVISIBLE (-2700 2250);
FORCEPROP 1 LAST TOLERANCE 5%
J 0
(-2675 2300);
DISPLAY 0.978723 (-2675 2300);
DISPLAY INVISIBLE (-2675 2300);
FORCEPROP 2 LAST CDS_LIB pure_quanta
J 0
(-2675 2400);
DISPLAY INVISIBLE (-2675 2400);
FORCEPROP 1 LAST PATH I108
J 0
(-2725 2550);
DISPLAY 0.978723 (-2725 2550);
PAINT WHITE (-2725 2550);
DISPLAY INVISIBLE (-2725 2550);
FORCEPROP 1 LAST PART_NUMBER CS24701JE04
J 0
(-2725 2500);
DISPLAY 0.978723 (-2725 2500);
DISPLAY INVISIBLE (-2725 2500);
FORCEADD OFFPAGE..1
R 2
(-2400 2800);
FORCEPROP 2 LAST $XR0 321 
J 0
(-2214 2800);
DISPLAY 0.638298 (-2214 2800);
PAINT MONO (-2214 2800);
FORCEPROP 2 LAST CDS_LIB standard
J 0
(-2400 2800);
DISPLAY INVISIBLE (-2400 2800);
FORCEPROP 1 LAST OFFPAGE TRUE
J 2
(-2725 2675);
DISPLAY 0.872340 (-2725 2675);
DISPLAY INVISIBLE (-2725 2675);
FORCEPROP 1 LAST COMMENT_BODY TRUE
J 2
(-2525 2700);
DISPLAY 0.872340 (-2525 2700);
PAINT GREEN (-2525 2700);
DISPLAY INVISIBLE (-2525 2700);
FORCEPROP 2 LAST PATH I109
J 0
(-2225 2875);
DISPLAY 0.680851 (-2225 2875);
DISPLAY INVISIBLE (-2225 2875);
FORCEADD OFFPAGE..3
R 2
(-7650 1650);
FORCEPROP 2 LAST $XR0 185 
J 0
(-7930 1650);
DISPLAY 0.638298 (-7930 1650);
PAINT MONO (-7930 1650);
FORCEPROP 2 LAST $XR1 186 
J 0
(-8050 1650);
DISPLAY 0.638298 (-8050 1650);
PAINT MONO (-8050 1650);
FORCEPROP 2 LAST CDS_LIB standard
J 0
(-7650 1650);
DISPLAY INVISIBLE (-7650 1650);
FORCEPROP 1 LAST OFFPAGE TRUE
J 2
(-7975 1525);
DISPLAY 0.872340 (-7975 1525);
PAINT GREEN (-7975 1525);
DISPLAY INVISIBLE (-7975 1525);
FORCEPROP 1 LAST COMMENT_BODY TRUE
J 2
(-7600 1550);
DISPLAY 0.872340 (-7600 1550);
PAINT GREEN (-7600 1550);
DISPLAY INVISIBLE (-7600 1550);
FORCEPROP 2 LAST PATH I11
J 0
(-7600 1725);
DISPLAY 0.680851 (-7600 1725);
DISPLAY INVISIBLE (-7600 1725);
FORCEADD Q_RES..1
(-2700 3350);
FORCEPROP 1 LAST LOCATION R1380
J 0
(-2825 3350);
DISPLAY 0.787234 (-2825 3350);
PAINT WHITE (-2825 3350);
FORCEPROP 0 LAST $SEC 1
J 0
(-2325 3400);
DISPLAY 0.680851 (-2325 3400);
PAINT MONO (-2325 3400);
DISPLAY INVISIBLE (-2325 3400);
FORCEPROP 0 LAST CDS_SEC 1
J 0
(-2325 3400);
DISPLAY 0.680851 (-2325 3400);
DISPLAY INVISIBLE (-2325 3400);
FORCEPROP 1 LASTPIN (-2800 3350) $PN 1
J 0
(-2788 3362);
DISPLAY 0.787234 (-2788 3362);
PAINT MONO (-2788 3362);
FORCEPROP 1 LASTPIN (-2600 3350) $PN 2
J 0
(-2638 3362);
DISPLAY 0.787234 (-2638 3362);
PAINT MONO (-2638 3362);
FORCEPROP 1 LAST MATERIAL CHIP
J 0
(-2475 3350);
DISPLAY 0.638298 (-2475 3350);
FORCEPROP 1 LAST PACK_TYPE 0201LF
J 0
(-2325 3350);
DISPLAY 0.638298 (-2325 3350);
FORCEPROP 1 LAST VALUE 1K
J 2
(-2500 3350);
DISPLAY 0.638298 (-2500 3350);
FORCEPROP 2 LAST CDS_LIB pure_quanta
J 0
(-2700 3350);
DISPLAY INVISIBLE (-2700 3350);
FORCEPROP 1 LAST WATTAGE 1/20W
J 2
(-2725 3200);
DISPLAY 0.638298 (-2725 3200);
DISPLAY INVISIBLE (-2725 3200);
FORCEPROP 1 LAST TOLERANCE 1%
J 0
(-2700 3250);
DISPLAY 0.638298 (-2700 3250);
DISPLAY INVISIBLE (-2700 3250);
FORCEPROP 1 LAST PATH I112
J 0
(-2750 3500);
DISPLAY 0.978723 (-2750 3500);
PAINT WHITE (-2750 3500);
DISPLAY INVISIBLE (-2750 3500);
FORCEPROP 1 LAST PART_NUMBER CS21001FE07
J 0
(-2750 3450);
DISPLAY 0.978723 (-2750 3450);
DISPLAY INVISIBLE (-2750 3450);
FORCEADD UNIVERSAL_GND..1
R 1
(-1950 2400);
FORCEPROP 3 LASTPIN (-2000 2400) SIG_NAME GND\g
J 0
(-1990 2410);
DISPLAY 0.659574 (-1990 2410);
PAINT MONO (-1990 2410);
DISPLAY INVISIBLE (-1990 2410);
FORCEPROP 2 LAST CDS_LIB pure_quanta_power
J 0
(-1950 2400);
DISPLAY INVISIBLE (-1950 2400);
FORCEPROP 1 LAST HDL_POWER GND
R 1
J 1
(-1875 2425);
DISPLAY 0.872340 (-1875 2425);
PAINT GREEN (-1875 2425);
DISPLAY INVISIBLE (-1875 2425);
FORCEPROP 1 LAST PATH I117
R 1
J 0
(-1950 2475);
DISPLAY 0.872340 (-1950 2475);
PAINT AQUA (-1950 2475);
DISPLAY INVISIBLE (-1950 2475);
FORCEADD GND..1
(-1525 3100);
FORCEPROP 3 LASTPIN (-1525 3150) SIG_NAME GND\g
J 0
(-1515 3160);
DISPLAY 0.659574 (-1515 3160);
PAINT MONO (-1515 3160);
DISPLAY INVISIBLE (-1515 3160);
FORCEPROP 2 LAST BOM_COST MEM
J 0
(-1625 3175);
DISPLAY 0.808511 (-1625 3175);
DISPLAY INVISIBLE (-1625 3175);
FORCEPROP 1 LAST SIZE 1B
J 0
(-1450 3050);
DISPLAY 0.851064 (-1450 3050);
PAINT GREEN (-1450 3050);
DISPLAY INVISIBLE (-1450 3050);
FORCEPROP 2 LAST CDS_LIB pure_quanta_power
J 0
(-1525 3100);
DISPLAY INVISIBLE (-1525 3100);
FORCEPROP 1 LAST HDL_POWER GND
J 0
(-1525 3250);
DISPLAY 0.851064 (-1525 3250);
PAINT GREEN (-1525 3250);
DISPLAY INVISIBLE (-1525 3250);
FORCEPROP 1 LAST PATH I118
J 0
(-1450 3100);
DISPLAY 0.872340 (-1450 3100);
PAINT AQUA (-1450 3100);
DISPLAY INVISIBLE (-1450 3100);
FORCEADD UNIVERSAL_GND..1
R 1
(-1950 3350);
FORCEPROP 3 LASTPIN (-2000 3350) SIG_NAME GND\g
J 0
(-1990 3360);
DISPLAY 0.659574 (-1990 3360);
PAINT MONO (-1990 3360);
DISPLAY INVISIBLE (-1990 3360);
FORCEPROP 2 LAST CDS_LIB pure_quanta_power
J 0
(-1950 3350);
DISPLAY INVISIBLE (-1950 3350);
FORCEPROP 1 LAST HDL_POWER GND
R 1
J 1
(-1875 3375);
DISPLAY 0.872340 (-1875 3375);
PAINT GREEN (-1875 3375);
DISPLAY INVISIBLE (-1875 3375);
FORCEPROP 1 LAST PATH I119
R 1
J 0
(-1950 3425);
DISPLAY 0.872340 (-1950 3425);
PAINT AQUA (-1950 3425);
DISPLAY INVISIBLE (-1950 3425);
FORCEADD Q_RES..2
(-1525 3500);
FORCEPROP 1 LAST LOCATION R1389
J 0
(-1480 3625);
DISPLAY 0.787234 (-1480 3625);
PAINT WHITE (-1480 3625);
FORCEPROP 0 LAST $SEC 1
J 0
(-1475 3675);
DISPLAY 0.680851 (-1475 3675);
PAINT MONO (-1475 3675);
DISPLAY INVISIBLE (-1475 3675);
FORCEPROP 0 LAST CDS_SEC 1
J 0
(-1475 3675);
DISPLAY 0.680851 (-1475 3675);
DISPLAY INVISIBLE (-1475 3675);
FORCEPROP 1 LASTPIN (-1525 3600) $PN 1
J 0
(-1520 3562);
DISPLAY 0.787234 (-1520 3562);
PAINT MONO (-1520 3562);
FORCEPROP 1 LASTPIN (-1525 3400) $PN 2
J 0
(-1520 3410);
DISPLAY 0.787234 (-1520 3410);
PAINT MONO (-1520 3410);
FORCEPROP 1 LAST TOLERANCE 1%
J 0
(-1480 3525);
DISPLAY 0.787234 (-1480 3525);
FORCEPROP 1 LAST VALUE 10K
J 0
(-1480 3575);
DISPLAY 0.787234 (-1480 3575);
FORCEPROP 1 LAST WATTAGE 1/20W
J 0
(-1485 3475);
DISPLAY 0.787234 (-1485 3475);
FORCEPROP 1 LAST PACK_TYPE 0201LF
J 0
(-1485 3325);
DISPLAY 0.787234 (-1485 3325);
FORCEPROP 1 LAST MATERIAL CHIP
J 0
(-1485 3425);
DISPLAY 0.787234 (-1485 3425);
FORCEPROP 2 LAST CDS_LIB pure_quanta
J 0
(-1525 3500);
DISPLAY INVISIBLE (-1525 3500);
FORCEPROP 1 LAST PATH I124
J 0
(-1475 3675);
DISPLAY 0.978723 (-1475 3675);
PAINT WHITE (-1475 3675);
DISPLAY INVISIBLE (-1475 3675);
FORCEPROP 1 LAST PART_NUMBER CS31001FE17
J 0
(-1485 3375);
DISPLAY 0.510638 (-1485 3375);
DISPLAY INVISIBLE (-1485 3375);
FORCEADD Q_RES..2
(-1525 4025);
FORCEPROP 1 LAST LOCATION R1388
J 0
(-1480 4150);
DISPLAY 0.787234 (-1480 4150);
PAINT WHITE (-1480 4150);
FORCEPROP 0 LAST $SEC 1
J 0
(-1475 4200);
DISPLAY 0.680851 (-1475 4200);
PAINT MONO (-1475 4200);
DISPLAY INVISIBLE (-1475 4200);
FORCEPROP 0 LAST CDS_SEC 1
J 0
(-1475 4200);
DISPLAY 0.680851 (-1475 4200);
DISPLAY INVISIBLE (-1475 4200);
FORCEPROP 1 LASTPIN (-1525 4125) $PN 1
J 0
(-1520 4087);
DISPLAY 0.787234 (-1520 4087);
PAINT MONO (-1520 4087);
FORCEPROP 1 LASTPIN (-1525 3925) $PN 2
J 0
(-1520 3935);
DISPLAY 0.787234 (-1520 3935);
PAINT MONO (-1520 3935);
FORCEPROP 1 LAST PACK_TYPE 0201LF
J 0
(-1485 3850);
DISPLAY 0.787234 (-1485 3850);
FORCEPROP 1 LAST TOLERANCE 1%
J 0
(-1480 4050);
DISPLAY 0.787234 (-1480 4050);
FORCEPROP 1 LAST WATTAGE 1/20W
J 0
(-1485 4000);
DISPLAY 0.787234 (-1485 4000);
FORCEPROP 1 LAST MATERIAL EMPTY
J 0
(-1485 3950);
DISPLAY 0.787234 (-1485 3950);
PAINT RED (-1485 3950);
FORCEPROP 1 LAST VALUE 1K
J 0
(-1480 4100);
DISPLAY 0.787234 (-1480 4100);
FORCEPROP 2 LAST CDS_LIB pure_quanta
J 0
(-1525 4025);
DISPLAY INVISIBLE (-1525 4025);
FORCEPROP 1 LAST PATH I125
J 0
(-1475 4200);
DISPLAY 0.978723 (-1475 4200);
PAINT WHITE (-1475 4200);
DISPLAY INVISIBLE (-1475 4200);
FORCEPROP 1 LAST PART_NUMBER CS21001FE07
J 0
(-1485 3900);
DISPLAY 0.978723 (-1485 3900);
DISPLAY INVISIBLE (-1485 3900);
FORCEADD OFFPAGE..1
R 2
(-675 3750);
FORCEPROP 2 LAST $XR0 321 
J 0
(-489 3750);
DISPLAY 0.638298 (-489 3750);
PAINT MONO (-489 3750);
FORCEPROP 2 LAST CDS_LIB standard
J 0
(-675 3750);
DISPLAY INVISIBLE (-675 3750);
FORCEPROP 1 LAST OFFPAGE TRUE
J 2
(-1000 3625);
DISPLAY 0.872340 (-1000 3625);
DISPLAY INVISIBLE (-1000 3625);
FORCEPROP 1 LAST COMMENT_BODY TRUE
J 2
(-800 3650);
DISPLAY 0.872340 (-800 3650);
PAINT GREEN (-800 3650);
DISPLAY INVISIBLE (-800 3650);
FORCEPROP 2 LAST PATH I126
J 0
(-500 3825);
DISPLAY 0.680851 (-500 3825);
DISPLAY INVISIBLE (-500 3825);
FORCEADD P1V0..1
(-1525 4425);
FORCEPROP 3 LASTPIN (-1525 4375) SIG_NAME P1V8_CPU1_RT_1D\g
J 0
(-1515 4385);
DISPLAY 0.659574 (-1515 4385);
PAINT MONO (-1515 4385);
DISPLAY INVISIBLE (-1515 4385);
FORCEPROP 1 LAST HDL_POWER P1V8_CPU1_RT_1D
J 1
(-1525 4475);
DISPLAY 0.489362 (-1525 4475);
PAINT SKYBLUE (-1525 4475);
FORCEPROP 2 LAST CDS_LIB pure_quanta_power
J 0
(-1525 4425);
DISPLAY INVISIBLE (-1525 4425);
FORCEPROP 1 LAST PATH I127
J 0
(-1475 4450);
DISPLAY 0.872340 (-1475 4450);
PAINT AQUA (-1475 4450);
DISPLAY INVISIBLE (-1475 4450);
FORCEADD Q_RES..2
(-8975 3550);
FORCEPROP 1 LAST LOCATION R6723
J 0
(-8930 3675);
DISPLAY 0.978723 (-8930 3675);
PAINT WHITE (-8930 3675);
FORCEPROP 0 LAST $SEC 1
J 0
(-8925 3725);
DISPLAY 0.680851 (-8925 3725);
PAINT MONO (-8925 3725);
DISPLAY INVISIBLE (-8925 3725);
FORCEPROP 0 LAST CDS_SEC 1
J 0
(-8925 3725);
DISPLAY 0.680851 (-8925 3725);
DISPLAY INVISIBLE (-8925 3725);
FORCEPROP 1 LASTPIN (-8975 3650) $PN 1
J 0
(-8970 3612);
DISPLAY 0.787234 (-8970 3612);
PAINT MONO (-8970 3612);
FORCEPROP 1 LASTPIN (-8975 3450) $PN 2
J 0
(-8970 3460);
DISPLAY 0.787234 (-8970 3460);
PAINT MONO (-8970 3460);
FORCEPROP 1 LAST VALUE 200
J 0
(-8930 3625);
DISPLAY 0.978723 (-8930 3625);
FORCEPROP 1 LAST PACK_TYPE 0201LF
J 0
(-8935 3375);
DISPLAY 0.978723 (-8935 3375);
FORCEPROP 1 LAST WATTAGE 1/20W
J 0
(-8935 3525);
DISPLAY 0.978723 (-8935 3525);
FORCEPROP 1 LAST TOLERANCE 1%
J 0
(-8930 3575);
DISPLAY 0.978723 (-8930 3575);
FORCEPROP 1 LAST MATERIAL CHIP
J 0
(-8935 3475);
DISPLAY 0.978723 (-8935 3475);
FORCEPROP 2 LAST CDS_LIB pure_quanta
J 0
(-8975 3550);
DISPLAY INVISIBLE (-8975 3550);
FORCEPROP 1 LAST PATH I128
J 0
(-8925 3725);
DISPLAY 0.978723 (-8925 3725);
PAINT WHITE (-8925 3725);
DISPLAY INVISIBLE (-8925 3725);
FORCEPROP 1 LAST PART_NUMBER CS12001FE12
J 0
(-8935 3425);
DISPLAY 0.978723 (-8935 3425);
DISPLAY INVISIBLE (-8935 3425);
FORCEADD Q_RES..1
(-6325 1650);
FORCEPROP 1 LAST LOCATION R675
J 0
(-6575 1675);
DISPLAY 0.978723 (-6575 1675);
FORCEPROP 0 LAST $SEC 1
J 0
(-6475 1725);
DISPLAY 0.680851 (-6475 1725);
PAINT MONO (-6475 1725);
DISPLAY INVISIBLE (-6475 1725);
FORCEPROP 0 LAST CDS_SEC 1
J 0
(-6475 1725);
DISPLAY 0.680851 (-6475 1725);
DISPLAY INVISIBLE (-6475 1725);
FORCEPROP 1 LASTPIN (-6425 1650) $PN 1
J 0
(-6413 1662);
DISPLAY 0.787234 (-6413 1662);
PAINT MONO (-6413 1662);
FORCEPROP 1 LASTPIN (-6225 1650) $PN 2
J 0
(-6263 1662);
DISPLAY 0.787234 (-6263 1662);
PAINT MONO (-6263 1662);
FORCEPROP 1 LAST MATERIAL CHIP
J 0
(-6650 1600);
DISPLAY 0.638298 (-6650 1600);
FORCEPROP 1 LAST TOLERANCE 1%
J 0
(-6375 1550);
DISPLAY 0.638298 (-6375 1550);
FORCEPROP 1 LAST WATTAGE 1/20W
J 2
(-6100 1550);
DISPLAY 0.638298 (-6100 1550);
FORCEPROP 1 LAST VALUE 49.9
J 2
(-6475 1550);
DISPLAY 0.638298 (-6475 1550);
FORCEPROP 1 LAST PACK_TYPE 0201LF
J 0
(-6125 1600);
DISPLAY 0.638298 (-6125 1600);
FORCEPROP 2 LAST CDS_LIB pure_quanta
J 0
(-6325 1650);
DISPLAY INVISIBLE (-6325 1650);
FORCEPROP 1 LAST PATH I13
J 0
(-6375 1800);
DISPLAY 0.978723 (-6375 1800);
PAINT WHITE (-6375 1800);
DISPLAY INVISIBLE (-6375 1800);
FORCEPROP 1 LAST PART_NUMBER CS04991FE06
J 0
(-6500 1600);
DISPLAY 0.638298 (-6500 1600);
DISPLAY INVISIBLE (-6500 1600);
FORCEADD OFFPAGE..5
(-2625 1025);
FORCEPROP 2 LAST $XR0 321 
J 0
(-2880 1025);
DISPLAY 0.638298 (-2880 1025);
PAINT MONO (-2880 1025);
FORCEPROP 2 LAST CDS_LIB standard
J 0
(-2625 1025);
DISPLAY INVISIBLE (-2625 1025);
FORCEPROP 1 LAST OFFPAGE TRUE
J 0
(-2300 900);
DISPLAY 0.872340 (-2300 900);
PAINT GREEN (-2300 900);
DISPLAY INVISIBLE (-2300 900);
FORCEPROP 1 LAST COMMENT_BODY TRUE
J 0
(-2525 950);
DISPLAY 0.872340 (-2525 950);
PAINT GREEN (-2525 950);
DISPLAY INVISIBLE (-2525 950);
FORCEPROP 2 LAST PATH I130
J 0
(-2575 1100);
DISPLAY 0.680851 (-2575 1100);
DISPLAY INVISIBLE (-2575 1100);
FORCEADD OFFPAGE..5
(-2625 975);
FORCEPROP 2 LAST $XR0 321 
J 0
(-2880 975);
DISPLAY 0.638298 (-2880 975);
PAINT MONO (-2880 975);
FORCEPROP 2 LAST CDS_LIB standard
J 0
(-2625 975);
DISPLAY INVISIBLE (-2625 975);
FORCEPROP 1 LAST OFFPAGE TRUE
J 0
(-2300 850);
DISPLAY 0.872340 (-2300 850);
PAINT GREEN (-2300 850);
DISPLAY INVISIBLE (-2300 850);
FORCEPROP 1 LAST COMMENT_BODY TRUE
J 0
(-2525 900);
DISPLAY 0.872340 (-2525 900);
PAINT GREEN (-2525 900);
DISPLAY INVISIBLE (-2525 900);
FORCEPROP 2 LAST PATH I131
J 0
(-2575 1050);
DISPLAY 0.680851 (-2575 1050);
DISPLAY INVISIBLE (-2575 1050);
FORCEADD OFFPAGE..5
(-2625 1075);
FORCEPROP 2 LAST $XR0 321 
J 0
(-2880 1075);
DISPLAY 0.638298 (-2880 1075);
PAINT MONO (-2880 1075);
FORCEPROP 2 LAST CDS_LIB standard
J 0
(-2625 1075);
DISPLAY INVISIBLE (-2625 1075);
FORCEPROP 1 LAST OFFPAGE TRUE
J 0
(-2300 950);
DISPLAY 0.872340 (-2300 950);
PAINT GREEN (-2300 950);
DISPLAY INVISIBLE (-2300 950);
FORCEPROP 1 LAST COMMENT_BODY TRUE
J 0
(-2525 1000);
DISPLAY 0.872340 (-2525 1000);
PAINT GREEN (-2525 1000);
DISPLAY INVISIBLE (-2525 1000);
FORCEPROP 2 LAST PATH I132
J 0
(-2575 1150);
DISPLAY 0.680851 (-2575 1150);
DISPLAY INVISIBLE (-2575 1150);
FORCEADD OFFPAGE..5
(-2625 1125);
FORCEPROP 2 LAST $XR0 321 
J 0
(-2880 1125);
DISPLAY 0.638298 (-2880 1125);
PAINT MONO (-2880 1125);
FORCEPROP 2 LAST CDS_LIB standard
J 2
(-2625 1125);
DISPLAY INVISIBLE (-2625 1125);
FORCEPROP 1 LAST OFFPAGE TRUE
J 0
(-2300 1000);
DISPLAY 0.872340 (-2300 1000);
PAINT GREEN (-2300 1000);
DISPLAY INVISIBLE (-2300 1000);
FORCEPROP 1 LAST COMMENT_BODY TRUE
J 0
(-2525 1050);
DISPLAY 0.872340 (-2525 1050);
PAINT GREEN (-2525 1050);
DISPLAY INVISIBLE (-2525 1050);
FORCEPROP 2 LAST PATH I133
J 0
(-2575 1200);
DISPLAY 0.680851 (-2575 1200);
DISPLAY INVISIBLE (-2575 1200);
FORCEADD OFFPAGE..5
(-7675 1750);
FORCEPROP 2 LAST $XR0 185 
J 0
(-7930 1750);
DISPLAY 0.638298 (-7930 1750);
PAINT MONO (-7930 1750);
FORCEPROP 2 LAST $XR1 186 
J 0
(-8050 1750);
DISPLAY 0.638298 (-8050 1750);
PAINT MONO (-8050 1750);
FORCEPROP 2 LAST CDS_LIB standard
J 0
(-7675 1750);
DISPLAY INVISIBLE (-7675 1750);
FORCEPROP 1 LAST OFFPAGE TRUE
J 0
(-7350 1625);
DISPLAY 0.872340 (-7350 1625);
PAINT GREEN (-7350 1625);
DISPLAY INVISIBLE (-7350 1625);
FORCEPROP 1 LAST COMMENT_BODY TRUE
J 0
(-7575 1675);
DISPLAY 0.872340 (-7575 1675);
PAINT GREEN (-7575 1675);
DISPLAY INVISIBLE (-7575 1675);
FORCEPROP 2 LAST PATH I14
J 0
(-7625 1825);
DISPLAY 0.680851 (-7625 1825);
DISPLAY INVISIBLE (-7625 1825);
FORCEADD GND..1
(-650 450);
FORCEPROP 3 LASTPIN (-650 500) SIG_NAME GND\g
J 0
(-640 510);
DISPLAY 0.659574 (-640 510);
PAINT MONO (-640 510);
DISPLAY INVISIBLE (-640 510);
FORCEPROP 1 LAST SIZE 1B
J 0
(-575 400);
DISPLAY 0.851064 (-575 400);
PAINT GREEN (-575 400);
DISPLAY INVISIBLE (-575 400);
FORCEPROP 2 LAST BOM_COST MEM
J 0
(-750 525);
DISPLAY 0.808511 (-750 525);
DISPLAY INVISIBLE (-750 525);
FORCEPROP 2 LAST CDS_LIB pure_quanta_power
J 0
(-650 450);
DISPLAY INVISIBLE (-650 450);
FORCEPROP 1 LAST HDL_POWER GND
J 0
(-650 600);
DISPLAY 0.851064 (-650 600);
PAINT GREEN (-650 600);
DISPLAY INVISIBLE (-650 600);
FORCEPROP 1 LAST PATH I143
J 0
(-575 450);
DISPLAY 0.872340 (-575 450);
PAINT AQUA (-575 450);
DISPLAY INVISIBLE (-575 450);
FORCEADD Q_RES..2
(-650 750);
FORCEPROP 1 LAST LOCATION R1381
J 0
(-605 875);
DISPLAY 0.787234 (-605 875);
FORCEPROP 0 LAST $SEC 1
J 0
(-600 925);
DISPLAY 0.680851 (-600 925);
PAINT MONO (-600 925);
DISPLAY INVISIBLE (-600 925);
FORCEPROP 0 LAST CDS_SEC 1
J 0
(-600 925);
DISPLAY 0.680851 (-600 925);
DISPLAY INVISIBLE (-600 925);
FORCEPROP 1 LASTPIN (-650 850) $PN 1
J 0
(-645 812);
DISPLAY 0.787234 (-645 812);
PAINT MONO (-645 812);
FORCEPROP 1 LASTPIN (-650 650) $PN 2
J 0
(-645 660);
DISPLAY 0.787234 (-645 660);
PAINT MONO (-645 660);
FORCEPROP 1 LAST WATTAGE 1/20W
J 0
(-610 725);
DISPLAY 0.787234 (-610 725);
FORCEPROP 1 LAST TOLERANCE 5%
J 0
(-605 775);
DISPLAY 0.787234 (-605 775);
FORCEPROP 1 LAST VALUE 4.7K
J 0
(-605 825);
DISPLAY 0.787234 (-605 825);
FORCEPROP 1 LAST PACK_TYPE 0201LF
J 0
(-610 575);
DISPLAY 0.787234 (-610 575);
FORCEPROP 1 LAST MATERIAL CHIP
J 0
(-610 675);
DISPLAY 0.787234 (-610 675);
FORCEPROP 2 LAST CDS_LIB pure_quanta
J 0
(-650 750);
DISPLAY INVISIBLE (-650 750);
FORCEPROP 1 LAST PATH I144
J 0
(-600 925);
DISPLAY 0.978723 (-600 925);
PAINT WHITE (-600 925);
DISPLAY INVISIBLE (-600 925);
FORCEPROP 1 LAST PART_NUMBER CS24701JE04
J 0
(-610 625);
DISPLAY 0.978723 (-610 625);
DISPLAY INVISIBLE (-610 625);
FORCEADD Q_RES..2
(-1200 1375);
FORCEPROP 1 LAST LOCATION R1465
J 0
(-1155 1500);
DISPLAY 0.978723 (-1155 1500);
FORCEPROP 0 LAST $SEC 1
J 0
(-1150 1550);
DISPLAY 0.680851 (-1150 1550);
PAINT MONO (-1150 1550);
DISPLAY INVISIBLE (-1150 1550);
FORCEPROP 0 LAST CDS_SEC 1
J 0
(-1150 1550);
DISPLAY 0.680851 (-1150 1550);
DISPLAY INVISIBLE (-1150 1550);
FORCEPROP 1 LASTPIN (-1200 1475) $PN 1
J 0
(-1195 1437);
DISPLAY 0.787234 (-1195 1437);
PAINT MONO (-1195 1437);
FORCEPROP 1 LASTPIN (-1200 1275) $PN 2
J 0
(-1195 1285);
DISPLAY 0.787234 (-1195 1285);
PAINT MONO (-1195 1285);
FORCEPROP 1 LAST TOLERANCE 5%
J 0
(-1155 1400);
DISPLAY 0.787234 (-1155 1400);
FORCEPROP 1 LAST VALUE 4.7K
J 0
(-1155 1450);
DISPLAY 0.787234 (-1155 1450);
FORCEPROP 1 LAST WATTAGE 1/20W
J 0
(-1160 1350);
DISPLAY 0.787234 (-1160 1350);
FORCEPROP 1 LAST MATERIAL EMPTY
J 0
(-1160 1300);
DISPLAY 0.787234 (-1160 1300);
PAINT RED (-1160 1300);
FORCEPROP 1 LAST PACK_TYPE 0201LF
J 0
(-1150 1225);
DISPLAY 0.787234 (-1150 1225);
FORCEPROP 2 LAST CDS_LIB pure_quanta
J 0
(-1200 1375);
DISPLAY INVISIBLE (-1200 1375);
FORCEPROP 1 LAST PATH I145
J 0
(-1150 1550);
DISPLAY 0.978723 (-1150 1550);
PAINT WHITE (-1150 1550);
DISPLAY INVISIBLE (-1150 1550);
FORCEPROP 1 LAST PART_NUMBER CS24701JE04
J 0
(-1160 1250);
DISPLAY 0.978723 (-1160 1250);
DISPLAY INVISIBLE (-1160 1250);
FORCEADD Q_RES..2
(-925 1375);
FORCEPROP 1 LAST LOCATION R1466
J 0
(-880 1500);
DISPLAY 0.978723 (-880 1500);
FORCEPROP 0 LAST $SEC 1
J 0
(-875 1550);
DISPLAY 0.680851 (-875 1550);
PAINT MONO (-875 1550);
DISPLAY INVISIBLE (-875 1550);
FORCEPROP 0 LAST CDS_SEC 1
J 0
(-875 1550);
DISPLAY 0.680851 (-875 1550);
DISPLAY INVISIBLE (-875 1550);
FORCEPROP 1 LASTPIN (-925 1475) $PN 1
J 0
(-920 1437);
DISPLAY 0.787234 (-920 1437);
PAINT MONO (-920 1437);
FORCEPROP 1 LASTPIN (-925 1275) $PN 2
J 0
(-920 1285);
DISPLAY 0.787234 (-920 1285);
PAINT MONO (-920 1285);
FORCEPROP 1 LAST VALUE 1K
J 0
(-880 1450);
DISPLAY 0.787234 (-880 1450);
FORCEPROP 1 LAST TOLERANCE 1%
J 0
(-880 1400);
DISPLAY 0.787234 (-880 1400);
FORCEPROP 1 LAST WATTAGE 1/20W
J 0
(-885 1350);
DISPLAY 0.787234 (-885 1350);
FORCEPROP 1 LAST MATERIAL EMPTY
J 0
(-885 1300);
DISPLAY 0.787234 (-885 1300);
PAINT RED (-885 1300);
FORCEPROP 1 LAST PACK_TYPE 0201LF
J 0
(-885 1200);
DISPLAY 0.787234 (-885 1200);
FORCEPROP 2 LAST CDS_LIB pure_quanta
J 0
(-925 1375);
DISPLAY INVISIBLE (-925 1375);
FORCEPROP 1 LAST PATH I146
J 0
(-875 1550);
DISPLAY 0.978723 (-875 1550);
PAINT WHITE (-875 1550);
DISPLAY INVISIBLE (-875 1550);
FORCEPROP 1 LAST PART_NUMBER CS21001FE07
J 0
(-885 1250);
DISPLAY 0.978723 (-885 1250);
DISPLAY INVISIBLE (-885 1250);
FORCEADD Q_RES..2
(-650 1400);
FORCEPROP 1 LAST LOCATION R1467
J 0
(-605 1525);
DISPLAY 0.787234 (-605 1525);
FORCEPROP 0 LAST $SEC 1
J 0
(-600 1575);
DISPLAY 0.680851 (-600 1575);
PAINT MONO (-600 1575);
DISPLAY INVISIBLE (-600 1575);
FORCEPROP 0 LAST CDS_SEC 1
J 0
(-600 1575);
DISPLAY 0.680851 (-600 1575);
DISPLAY INVISIBLE (-600 1575);
FORCEPROP 1 LASTPIN (-650 1500) $PN 1
J 0
(-645 1462);
DISPLAY 0.787234 (-645 1462);
PAINT MONO (-645 1462);
FORCEPROP 1 LASTPIN (-650 1300) $PN 2
J 0
(-645 1310);
DISPLAY 0.787234 (-645 1310);
PAINT MONO (-645 1310);
FORCEPROP 1 LAST TOLERANCE 5%
J 0
(-605 1425);
DISPLAY 0.787234 (-605 1425);
FORCEPROP 1 LAST VALUE 4.7K
J 0
(-605 1475);
DISPLAY 0.787234 (-605 1475);
FORCEPROP 1 LAST WATTAGE 1/20W
J 0
(-610 1375);
DISPLAY 0.787234 (-610 1375);
FORCEPROP 1 LAST MATERIAL EMPTY
J 0
(-610 1325);
DISPLAY 0.787234 (-610 1325);
PAINT RED (-610 1325);
FORCEPROP 1 LAST PACK_TYPE 0201LF
J 0
(-600 1250);
DISPLAY 0.787234 (-600 1250);
FORCEPROP 2 LAST CDS_LIB pure_quanta
J 2
(-650 1400);
DISPLAY INVISIBLE (-650 1400);
FORCEPROP 1 LAST PATH I147
J 0
(-600 1575);
DISPLAY 0.978723 (-600 1575);
PAINT WHITE (-600 1575);
DISPLAY INVISIBLE (-600 1575);
FORCEPROP 1 LAST PART_NUMBER CS24701JE04
J 0
(-610 1275);
DISPLAY 0.978723 (-610 1275);
DISPLAY INVISIBLE (-610 1275);
FORCEADD P1V0..1
(-650 1700);
FORCEPROP 3 LASTPIN (-650 1650) SIG_NAME P1V8_CPU1_RT_1D\g
J 0
(-640 1660);
DISPLAY 0.659574 (-640 1660);
PAINT MONO (-640 1660);
DISPLAY INVISIBLE (-640 1660);
FORCEPROP 1 LAST HDL_POWER P1V8_CPU1_RT_1D
J 1
(-650 1750);
DISPLAY 0.489362 (-650 1750);
PAINT SKYBLUE (-650 1750);
FORCEPROP 2 LAST CDS_LIB pure_quanta_power
J 0
(-650 1700);
DISPLAY INVISIBLE (-650 1700);
FORCEPROP 1 LAST PATH I148
J 0
(-600 1725);
DISPLAY 0.872340 (-600 1725);
PAINT AQUA (-600 1725);
DISPLAY INVISIBLE (-600 1725);
FORCEADD Q_RES..2
(-1475 1375);
FORCEPROP 1 LAST LOCATION R1464
J 0
(-1430 1500);
DISPLAY 0.978723 (-1430 1500);
FORCEPROP 0 LAST $SEC 1
J 0
(-1425 1550);
DISPLAY 0.680851 (-1425 1550);
PAINT MONO (-1425 1550);
DISPLAY INVISIBLE (-1425 1550);
FORCEPROP 0 LAST CDS_SEC 1
J 0
(-1425 1550);
DISPLAY 0.680851 (-1425 1550);
DISPLAY INVISIBLE (-1425 1550);
FORCEPROP 1 LASTPIN (-1475 1475) $PN 1
J 0
(-1470 1437);
DISPLAY 0.787234 (-1470 1437);
PAINT MONO (-1470 1437);
FORCEPROP 1 LASTPIN (-1475 1275) $PN 2
J 0
(-1470 1285);
DISPLAY 0.787234 (-1470 1285);
PAINT MONO (-1470 1285);
FORCEPROP 1 LAST TOLERANCE 5%
J 0
(-1430 1400);
DISPLAY 0.787234 (-1430 1400);
FORCEPROP 1 LAST VALUE 4.7K
J 0
(-1430 1450);
DISPLAY 0.787234 (-1430 1450);
FORCEPROP 1 LAST WATTAGE 1/20W
J 0
(-1435 1350);
DISPLAY 0.787234 (-1435 1350);
FORCEPROP 1 LAST MATERIAL EMPTY
J 0
(-1435 1300);
DISPLAY 0.787234 (-1435 1300);
PAINT RED (-1435 1300);
FORCEPROP 1 LAST PACK_TYPE 0201LF
J 0
(-1425 1225);
DISPLAY 0.787234 (-1425 1225);
FORCEPROP 2 LAST CDS_LIB pure_quanta
J 0
(-1475 1375);
DISPLAY INVISIBLE (-1475 1375);
FORCEPROP 1 LAST PATH I149
J 0
(-1425 1550);
DISPLAY 0.978723 (-1425 1550);
PAINT WHITE (-1425 1550);
DISPLAY INVISIBLE (-1425 1550);
FORCEPROP 1 LAST PART_NUMBER CS24701JE04
J 0
(-1435 1250);
DISPLAY 0.978723 (-1435 1250);
DISPLAY INVISIBLE (-1435 1250);
FORCEADD OFFPAGE..1
R 2
(-2725 3750);
FORCEPROP 2 LAST $XR0 321 
J 0
(-2539 3750);
DISPLAY 0.638298 (-2539 3750);
PAINT MONO (-2539 3750);
FORCEPROP 2 LAST CDS_LIB standard
J 0
(-2725 3750);
DISPLAY INVISIBLE (-2725 3750);
FORCEPROP 1 LAST OFFPAGE TRUE
J 2
(-3050 3625);
DISPLAY 0.872340 (-3050 3625);
DISPLAY INVISIBLE (-3050 3625);
FORCEPROP 1 LAST COMMENT_BODY TRUE
J 2
(-2850 3650);
DISPLAY 0.872340 (-2850 3650);
PAINT GREEN (-2850 3650);
DISPLAY INVISIBLE (-2850 3650);
FORCEPROP 2 LAST PATH I151
J 0
(-2550 3825);
DISPLAY 0.680851 (-2550 3825);
DISPLAY INVISIBLE (-2550 3825);
FORCEADD OFFPAGE..1
R 2
(-2725 3650);
FORCEPROP 2 LAST $XR0 321 
J 0
(-2539 3650);
DISPLAY 0.638298 (-2539 3650);
PAINT MONO (-2539 3650);
FORCEPROP 2 LAST CDS_LIB standard
J 0
(-2725 3650);
DISPLAY INVISIBLE (-2725 3650);
FORCEPROP 1 LAST OFFPAGE TRUE
J 2
(-3050 3525);
DISPLAY 0.872340 (-3050 3525);
DISPLAY INVISIBLE (-3050 3525);
FORCEPROP 1 LAST COMMENT_BODY TRUE
J 2
(-2850 3550);
DISPLAY 0.872340 (-2850 3550);
PAINT GREEN (-2850 3550);
DISPLAY INVISIBLE (-2850 3550);
FORCEPROP 2 LAST PATH I152
J 0
(-2550 3725);
DISPLAY 0.680851 (-2550 3725);
DISPLAY INVISIBLE (-2550 3725);
FORCEADD OFFPAGE..1
R 2
(-2725 3550);
FORCEPROP 2 LAST $XR0 321 
J 0
(-2539 3550);
DISPLAY 0.638298 (-2539 3550);
PAINT MONO (-2539 3550);
FORCEPROP 2 LAST CDS_LIB standard
J 0
(-2725 3550);
DISPLAY INVISIBLE (-2725 3550);
FORCEPROP 1 LAST OFFPAGE TRUE
J 2
(-3050 3425);
DISPLAY 0.872340 (-3050 3425);
DISPLAY INVISIBLE (-3050 3425);
FORCEPROP 1 LAST COMMENT_BODY TRUE
J 2
(-2850 3450);
DISPLAY 0.872340 (-2850 3450);
PAINT GREEN (-2850 3450);
DISPLAY INVISIBLE (-2850 3450);
FORCEPROP 2 LAST PATH I153
J 0
(-2550 3625);
DISPLAY 0.680851 (-2550 3625);
DISPLAY INVISIBLE (-2550 3625);
FORCEADD OFFPAGE..1
R 2
(-2750 3450);
FORCEPROP 2 LAST $XR0 321 
J 0
(-2564 3450);
DISPLAY 0.638298 (-2564 3450);
PAINT MONO (-2564 3450);
FORCEPROP 2 LAST CDS_LIB standard
J 0
(-2750 3450);
DISPLAY INVISIBLE (-2750 3450);
FORCEPROP 1 LAST OFFPAGE TRUE
J 2
(-3075 3325);
DISPLAY 0.872340 (-3075 3325);
DISPLAY INVISIBLE (-3075 3325);
FORCEPROP 1 LAST COMMENT_BODY TRUE
J 2
(-2875 3350);
DISPLAY 0.872340 (-2875 3350);
PAINT GREEN (-2875 3350);
DISPLAY INVISIBLE (-2875 3350);
FORCEPROP 2 LAST PATH I154
J 0
(-2575 3525);
DISPLAY 0.680851 (-2575 3525);
DISPLAY INVISIBLE (-2575 3525);
FORCEADD Q_RES..1
(-6325 1750);
FORCEPROP 1 LAST LOCATION R674
J 0
(-6575 1750);
DISPLAY 0.978723 (-6575 1750);
FORCEPROP 2 LAST SEC 1
J 0
(-6375 1950);
DISPLAY 0.680851 (-6375 1950);
PAINT MONO (-6375 1950);
DISPLAY INVISIBLE (-6375 1950);
FORCEPROP 1 LASTPIN (-6425 1750) $PN 1
J 0
(-6413 1762);
DISPLAY 0.787234 (-6413 1762);
PAINT MONO (-6413 1762);
FORCEPROP 1 LASTPIN (-6225 1750) $PN 2
J 0
(-6263 1762);
DISPLAY 0.787234 (-6263 1762);
PAINT MONO (-6263 1762);
FORCEPROP 1 LAST MATERIAL CHIP
J 0
(-6400 1825);
DISPLAY 0.638298 (-6400 1825);
FORCEPROP 1 LAST PACK_TYPE 0201LF
J 0
(-6250 1825);
DISPLAY 0.638298 (-6250 1825);
FORCEPROP 1 LAST WATTAGE 1/20W
J 2
(-6425 1825);
DISPLAY 0.638298 (-6425 1825);
FORCEPROP 1 LAST TOLERANCE 1%
J 0
(-6450 1875);
DISPLAY 0.638298 (-6450 1875);
FORCEPROP 1 LAST VALUE 22
J 2
(-6500 1875);
DISPLAY 0.638298 (-6500 1875);
FORCEPROP 2 LAST SEC_TYPE 0201LF
J 0
(-6375 1950);
DISPLAY 0.680851 (-6375 1950);
DISPLAY INVISIBLE (-6375 1950);
FORCEPROP 2 LAST CDS_LIB pure_quanta
J 0
(-6325 1750);
DISPLAY INVISIBLE (-6325 1750);
FORCEPROP 1 LAST PATH I155
J 0
(-6375 1900);
DISPLAY 0.978723 (-6375 1900);
PAINT WHITE (-6375 1900);
DISPLAY INVISIBLE (-6375 1900);
FORCEPROP 1 LAST PART_NUMBER CS02201FE11
J 0
(-6375 1875);
DISPLAY 0.638298 (-6375 1875);
DISPLAY INVISIBLE (-6375 1875);
FORCEADD OFFPAGE..1
(-6025 3450);
FORCEPROP 2 LAST $XR0 321 
J 0
(-6307 3450);
DISPLAY 0.638298 (-6307 3450);
PAINT MONO (-6307 3450);
FORCEPROP 2 LAST CDS_LIB standard
J 0
(-6025 3450);
DISPLAY INVISIBLE (-6025 3450);
FORCEPROP 1 LAST OFFPAGE TRUE
J 0
(-5700 3325);
DISPLAY 0.872340 (-5700 3325);
DISPLAY INVISIBLE (-5700 3325);
FORCEPROP 1 LAST COMMENT_BODY TRUE
J 0
(-5900 3350);
DISPLAY 0.872340 (-5900 3350);
PAINT GREEN (-5900 3350);
DISPLAY INVISIBLE (-5900 3350);
FORCEPROP 2 LAST PATH I17
J 0
(-5975 3525);
DISPLAY 0.680851 (-5975 3525);
DISPLAY INVISIBLE (-5975 3525);
FORCEADD OFFPAGE..1
(-6025 3350);
FORCEPROP 2 LAST $XR0 321 
J 0
(-6307 3350);
DISPLAY 0.638298 (-6307 3350);
PAINT MONO (-6307 3350);
FORCEPROP 2 LAST CDS_LIB standard
J 0
(-6025 3350);
DISPLAY INVISIBLE (-6025 3350);
FORCEPROP 1 LAST OFFPAGE TRUE
J 0
(-5700 3225);
DISPLAY 0.872340 (-5700 3225);
DISPLAY INVISIBLE (-5700 3225);
FORCEPROP 1 LAST COMMENT_BODY TRUE
J 0
(-5900 3250);
DISPLAY 0.872340 (-5900 3250);
PAINT GREEN (-5900 3250);
DISPLAY INVISIBLE (-5900 3250);
FORCEPROP 2 LAST PATH I18
J 0
(-5975 3425);
DISPLAY 0.680851 (-5975 3425);
DISPLAY INVISIBLE (-5975 3425);
FORCEADD Q_RES..1
(-6350 3000);
FORCEPROP 1 LAST LOCATION R6812
J 0
(-6600 3025);
DISPLAY 0.978723 (-6600 3025);
FORCEPROP 0 LAST $SEC 1
J 0
(-6400 3175);
DISPLAY 0.680851 (-6400 3175);
PAINT MONO (-6400 3175);
DISPLAY INVISIBLE (-6400 3175);
FORCEPROP 0 LAST CDS_SEC 1
J 0
(-6400 3175);
DISPLAY 0.680851 (-6400 3175);
DISPLAY INVISIBLE (-6400 3175);
FORCEPROP 1 LASTPIN (-6450 3000) $PN 1
J 0
(-6438 3012);
DISPLAY 0.787234 (-6438 3012);
PAINT MONO (-6438 3012);
FORCEPROP 1 LASTPIN (-6250 3000) $PN 2
J 0
(-6288 3012);
DISPLAY 0.787234 (-6288 3012);
PAINT MONO (-6288 3012);
FORCEPROP 1 LAST MATERIAL CHIP
J 0
(-6525 3075);
DISPLAY 0.787234 (-6525 3075);
FORCEPROP 1 LAST VALUE 0
J 2
(-6550 3125);
DISPLAY 0.787234 (-6550 3125);
FORCEPROP 1 LAST TOLERANCE 5%
J 0
(-6525 3125);
DISPLAY 0.787234 (-6525 3125);
FORCEPROP 1 LAST PACK_TYPE 0201LF
J 0
(-6325 3075);
DISPLAY 0.787234 (-6325 3075);
FORCEPROP 1 LAST WATTAGE 1/20W
J 2
(-6550 3075);
DISPLAY 0.787234 (-6550 3075);
FORCEPROP 2 LAST CDS_LIB pure_quanta
J 0
(-6350 3000);
DISPLAY INVISIBLE (-6350 3000);
FORCEPROP 1 LAST PATH I19
J 0
(-6400 3150);
DISPLAY 0.978723 (-6400 3150);
PAINT WHITE (-6400 3150);
DISPLAY INVISIBLE (-6400 3150);
FORCEPROP 1 LAST PART_NUMBER CS00001JE10
J 0
(-6400 3125);
DISPLAY 0.808511 (-6400 3125);
DISPLAY INVISIBLE (-6400 3125);
FORCEADD OFFPAGE..1
(-8050 1300);
FORCEPROP 2 LAST $XR0 183 
J 0
(-8332 1300);
DISPLAY 0.638298 (-8332 1300);
PAINT MONO (-8332 1300);
FORCEPROP 2 LAST CDS_LIB standard
J 0
(-8050 1300);
DISPLAY INVISIBLE (-8050 1300);
FORCEPROP 1 LAST OFFPAGE TRUE
J 0
(-7725 1175);
DISPLAY 0.872340 (-7725 1175);
DISPLAY INVISIBLE (-7725 1175);
FORCEPROP 1 LAST COMMENT_BODY TRUE
J 0
(-7925 1200);
DISPLAY 0.872340 (-7925 1200);
PAINT GREEN (-7925 1200);
DISPLAY INVISIBLE (-7925 1200);
FORCEPROP 2 LAST PATH I2
J 0
(-8000 1375);
DISPLAY 0.680851 (-8000 1375);
DISPLAY INVISIBLE (-8000 1375);
FORCEADD Q_RES..1
(-6350 2900);
FORCEPROP 1 LAST LOCATION R6813
J 0
(-6600 2925);
DISPLAY 0.978723 (-6600 2925);
FORCEPROP 0 LAST $SEC 1
J 0
(-6600 2975);
DISPLAY 0.680851 (-6600 2975);
PAINT MONO (-6600 2975);
DISPLAY INVISIBLE (-6600 2975);
FORCEPROP 0 LAST CDS_SEC 1
J 0
(-6600 2975);
DISPLAY 0.680851 (-6600 2975);
DISPLAY INVISIBLE (-6600 2975);
FORCEPROP 1 LASTPIN (-6450 2900) $PN 1
J 0
(-6438 2912);
DISPLAY 0.787234 (-6438 2912);
PAINT MONO (-6438 2912);
FORCEPROP 1 LASTPIN (-6250 2900) $PN 2
J 0
(-6288 2912);
DISPLAY 0.787234 (-6288 2912);
PAINT MONO (-6288 2912);
FORCEPROP 2 LAST CDS_LIB pure_quanta
J 0
(-6350 2900);
DISPLAY INVISIBLE (-6350 2900);
FORCEPROP 1 LAST PACK_TYPE 0201LF
J 0
(-6325 2975);
DISPLAY 0.787234 (-6325 2975);
DISPLAY INVISIBLE (-6325 2975);
FORCEPROP 1 LAST MATERIAL CHIP
J 0
(-6525 2975);
DISPLAY 0.787234 (-6525 2975);
DISPLAY INVISIBLE (-6525 2975);
FORCEPROP 1 LAST TOLERANCE 5%
J 0
(-6525 3025);
DISPLAY 0.787234 (-6525 3025);
DISPLAY INVISIBLE (-6525 3025);
FORCEPROP 1 LAST VALUE 0
J 2
(-6550 3025);
DISPLAY 0.787234 (-6550 3025);
DISPLAY INVISIBLE (-6550 3025);
FORCEPROP 1 LAST WATTAGE 1/20W
J 2
(-6550 2975);
DISPLAY 0.787234 (-6550 2975);
DISPLAY INVISIBLE (-6550 2975);
FORCEPROP 1 LAST PATH I20
J 0
(-6400 3050);
DISPLAY 0.978723 (-6400 3050);
PAINT WHITE (-6400 3050);
DISPLAY INVISIBLE (-6400 3050);
FORCEPROP 1 LAST PART_NUMBER CS00001JE10
J 0
(-6400 3025);
DISPLAY 0.808511 (-6400 3025);
DISPLAY INVISIBLE (-6400 3025);
FORCEADD OFFPAGE..1
(-7650 3000);
FORCEPROP 2 LAST $XR0 184 
J 0
(-7902 3000);
DISPLAY 0.638298 (-7902 3000);
PAINT MONO (-7902 3000);
FORCEPROP 2 LAST CDS_LIB standard
J 0
(-7650 3000);
DISPLAY INVISIBLE (-7650 3000);
FORCEPROP 1 LAST OFFPAGE TRUE
J 0
(-7325 2875);
DISPLAY 0.872340 (-7325 2875);
DISPLAY INVISIBLE (-7325 2875);
FORCEPROP 1 LAST COMMENT_BODY TRUE
J 0
(-7525 2900);
DISPLAY 0.872340 (-7525 2900);
PAINT GREEN (-7525 2900);
DISPLAY INVISIBLE (-7525 2900);
FORCEPROP 2 LAST PATH I21
J 0
(-7600 3075);
DISPLAY 0.680851 (-7600 3075);
DISPLAY INVISIBLE (-7600 3075);
FORCEADD OFFPAGE..3
R 2
(-7650 2900);
FORCEPROP 2 LAST $XR0 184 
J 0
(-7930 2900);
DISPLAY 0.638298 (-7930 2900);
PAINT MONO (-7930 2900);
FORCEPROP 2 LAST CDS_LIB standard
J 0
(-7650 2900);
DISPLAY INVISIBLE (-7650 2900);
FORCEPROP 1 LAST OFFPAGE TRUE
J 2
(-7975 2775);
DISPLAY 0.872340 (-7975 2775);
PAINT GREEN (-7975 2775);
DISPLAY INVISIBLE (-7975 2775);
FORCEPROP 1 LAST COMMENT_BODY TRUE
J 2
(-7600 2800);
DISPLAY 0.872340 (-7600 2800);
PAINT GREEN (-7600 2800);
DISPLAY INVISIBLE (-7600 2800);
FORCEPROP 2 LAST PATH I22
J 0
(-7600 2975);
DISPLAY 0.680851 (-7600 2975);
DISPLAY INVISIBLE (-7600 2975);
FORCEADD Q_RES..2
R 2
(-6300 825);
FORCEPROP 1 LAST LOCATION R627
J 2
(-6345 950);
DISPLAY 0.978723 (-6345 950);
FORCEPROP 0 LAST $SEC 1
J 0
(-6325 1000);
DISPLAY 0.680851 (-6325 1000);
PAINT MONO (-6325 1000);
DISPLAY INVISIBLE (-6325 1000);
FORCEPROP 0 LAST CDS_SEC 1
J 0
(-6325 1000);
DISPLAY 0.680851 (-6325 1000);
DISPLAY INVISIBLE (-6325 1000);
FORCEPROP 1 LASTPIN (-6300 925) $PN 1
J 2
(-6305 887);
DISPLAY 0.787234 (-6305 887);
PAINT MONO (-6305 887);
FORCEPROP 1 LASTPIN (-6300 725) $PN 2
J 2
(-6305 735);
DISPLAY 0.787234 (-6305 735);
PAINT MONO (-6305 735);
FORCEPROP 1 LAST TOLERANCE 1%
J 2
(-6345 850);
DISPLAY 0.978723 (-6345 850);
FORCEPROP 1 LAST MATERIAL EMPTY
J 2
(-6340 750);
DISPLAY 0.978723 (-6340 750);
FORCEPROP 1 LAST PACK_TYPE 0201LF
J 2
(-6340 650);
DISPLAY 0.978723 (-6340 650);
FORCEPROP 1 LAST WATTAGE 1/20W
J 2
(-6340 800);
DISPLAY 0.978723 (-6340 800);
FORCEPROP 1 LAST VALUE 51.1
J 2
(-6345 900);
DISPLAY 0.978723 (-6345 900);
FORCEPROP 2 LAST CDS_LIB pure_quanta
J 0
(-6300 825);
DISPLAY INVISIBLE (-6300 825);
FORCEPROP 1 LAST PATH I23
J 2
(-6350 1000);
DISPLAY 0.978723 (-6350 1000);
PAINT WHITE (-6350 1000);
DISPLAY INVISIBLE (-6350 1000);
FORCEPROP 1 LAST PART_NUMBER CS05111FE00
J 2
(-6340 700);
DISPLAY 0.978723 (-6340 700);
DISPLAY INVISIBLE (-6340 700);
FORCEADD Q_RES..2
(-6150 825);
FORCEPROP 1 LAST LOCATION R628
J 0
(-6105 950);
DISPLAY 0.978723 (-6105 950);
FORCEPROP 0 LAST $SEC 1
J 0
(-6100 1000);
DISPLAY 0.680851 (-6100 1000);
PAINT MONO (-6100 1000);
DISPLAY INVISIBLE (-6100 1000);
FORCEPROP 0 LAST CDS_SEC 1
J 0
(-6100 1000);
DISPLAY 0.680851 (-6100 1000);
DISPLAY INVISIBLE (-6100 1000);
FORCEPROP 1 LASTPIN (-6150 925) $PN 1
J 0
(-6145 887);
DISPLAY 0.787234 (-6145 887);
PAINT MONO (-6145 887);
FORCEPROP 1 LASTPIN (-6150 725) $PN 2
J 0
(-6145 735);
DISPLAY 0.787234 (-6145 735);
PAINT MONO (-6145 735);
FORCEPROP 1 LAST PACK_TYPE 0201LF
J 0
(-6110 650);
DISPLAY 0.978723 (-6110 650);
FORCEPROP 1 LAST TOLERANCE 1%
J 0
(-6105 850);
DISPLAY 0.978723 (-6105 850);
FORCEPROP 1 LAST MATERIAL EMPTY
J 0
(-6110 750);
DISPLAY 0.978723 (-6110 750);
FORCEPROP 1 LAST WATTAGE 1/20W
J 0
(-6110 800);
DISPLAY 0.978723 (-6110 800);
FORCEPROP 1 LAST VALUE 51.1
J 0
(-6105 900);
DISPLAY 0.978723 (-6105 900);
FORCEPROP 2 LAST CDS_LIB pure_quanta
J 0
(-6150 825);
DISPLAY INVISIBLE (-6150 825);
FORCEPROP 1 LAST PATH I24
J 0
(-6100 1000);
DISPLAY 0.978723 (-6100 1000);
PAINT WHITE (-6100 1000);
DISPLAY INVISIBLE (-6100 1000);
FORCEPROP 1 LAST PART_NUMBER CS05111FE00
J 0
(-6110 700);
DISPLAY 0.978723 (-6110 700);
DISPLAY INVISIBLE (-6110 700);
FORCEADD Q_RES..2
(-7725 6075);
FORCEPROP 1 LAST LOCATION R724
J 0
(-7680 6200);
DISPLAY 0.787234 (-7680 6200);
FORCEPROP 0 LAST $SEC 1
J 0
(-7675 6250);
DISPLAY 0.680851 (-7675 6250);
PAINT MONO (-7675 6250);
DISPLAY INVISIBLE (-7675 6250);
FORCEPROP 0 LAST CDS_SEC 1
J 0
(-7675 6250);
DISPLAY 0.680851 (-7675 6250);
DISPLAY INVISIBLE (-7675 6250);
FORCEPROP 1 LASTPIN (-7725 6175) $PN 1
J 0
(-7720 6137);
DISPLAY 0.787234 (-7720 6137);
PAINT MONO (-7720 6137);
FORCEPROP 1 LASTPIN (-7725 5975) $PN 2
J 0
(-7720 5985);
DISPLAY 0.787234 (-7720 5985);
PAINT MONO (-7720 5985);
FORCEPROP 1 LAST TOLERANCE 5%
J 0
(-7680 6100);
DISPLAY 0.787234 (-7680 6100);
FORCEPROP 1 LAST VALUE 4.7K
J 0
(-7680 6150);
DISPLAY 0.787234 (-7680 6150);
FORCEPROP 1 LAST MATERIAL EMPTY
J 0
(-7685 6000);
DISPLAY 0.787234 (-7685 6000);
FORCEPROP 1 LAST PACK_TYPE 0201LF
J 0
(-7685 5900);
DISPLAY 0.787234 (-7685 5900);
FORCEPROP 1 LAST WATTAGE 1/20W
J 0
(-7685 6050);
DISPLAY 0.787234 (-7685 6050);
FORCEPROP 2 LAST CDS_LIB pure_quanta
J 0
(-7725 6075);
DISPLAY INVISIBLE (-7725 6075);
FORCEPROP 1 LAST PATH I25
J 0
(-7675 6250);
DISPLAY 0.978723 (-7675 6250);
PAINT WHITE (-7675 6250);
DISPLAY INVISIBLE (-7675 6250);
FORCEPROP 1 LAST PART_NUMBER CS24701JE04
J 0
(-7685 5950);
DISPLAY 0.787234 (-7685 5950);
DISPLAY INVISIBLE (-7685 5950);
FORCEADD Q_RES..2
(-8025 6050);
FORCEPROP 1 LAST LOCATION R720
J 0
(-7980 6175);
DISPLAY 0.787234 (-7980 6175);
FORCEPROP 0 LAST $SEC 1
J 0
(-7975 6225);
DISPLAY 0.680851 (-7975 6225);
PAINT MONO (-7975 6225);
DISPLAY INVISIBLE (-7975 6225);
FORCEPROP 0 LAST CDS_SEC 1
J 0
(-7975 6225);
DISPLAY 0.680851 (-7975 6225);
DISPLAY INVISIBLE (-7975 6225);
FORCEPROP 1 LASTPIN (-8025 6150) $PN 1
J 0
(-8020 6112);
DISPLAY 0.787234 (-8020 6112);
PAINT MONO (-8020 6112);
FORCEPROP 1 LASTPIN (-8025 5950) $PN 2
J 0
(-8020 5960);
DISPLAY 0.787234 (-8020 5960);
PAINT MONO (-8020 5960);
FORCEPROP 1 LAST WATTAGE 1/20W
J 0
(-7985 6025);
DISPLAY 0.787234 (-7985 6025);
FORCEPROP 1 LAST TOLERANCE 5%
J 0
(-7980 6075);
DISPLAY 0.787234 (-7980 6075);
FORCEPROP 1 LAST VALUE 4.7K
J 0
(-7980 6125);
DISPLAY 0.787234 (-7980 6125);
FORCEPROP 1 LAST PACK_TYPE 0201LF
J 0
(-7975 5900);
DISPLAY 0.787234 (-7975 5900);
FORCEPROP 1 LAST MATERIAL EMPTY
J 0
(-7985 5975);
DISPLAY 0.787234 (-7985 5975);
FORCEPROP 2 LAST CDS_LIB pure_quanta
J 0
(-8025 6050);
DISPLAY INVISIBLE (-8025 6050);
FORCEPROP 1 LAST PATH I26
J 0
(-7975 6225);
DISPLAY 0.978723 (-7975 6225);
PAINT WHITE (-7975 6225);
DISPLAY INVISIBLE (-7975 6225);
FORCEPROP 1 LAST PART_NUMBER CS24701JE04
J 0
(-7985 5925);
DISPLAY 0.978723 (-7985 5925);
DISPLAY INVISIBLE (-7985 5925);
FORCEADD Q_RES..2
(-8325 6100);
FORCEPROP 1 LAST LOCATION R716
J 0
(-8280 6225);
DISPLAY 0.787234 (-8280 6225);
FORCEPROP 0 LAST $SEC 1
J 0
(-8275 6275);
DISPLAY 0.680851 (-8275 6275);
PAINT MONO (-8275 6275);
DISPLAY INVISIBLE (-8275 6275);
FORCEPROP 0 LAST CDS_SEC 1
J 0
(-8275 6275);
DISPLAY 0.680851 (-8275 6275);
DISPLAY INVISIBLE (-8275 6275);
FORCEPROP 1 LASTPIN (-8325 6200) $PN 1
J 0
(-8320 6162);
DISPLAY 0.787234 (-8320 6162);
PAINT MONO (-8320 6162);
FORCEPROP 1 LASTPIN (-8325 6000) $PN 2
J 0
(-8320 6010);
DISPLAY 0.787234 (-8320 6010);
PAINT MONO (-8320 6010);
FORCEPROP 1 LAST TOLERANCE 5%
J 0
(-8280 6125);
DISPLAY 0.787234 (-8280 6125);
FORCEPROP 1 LAST PACK_TYPE 0201LF
J 0
(-8275 5950);
DISPLAY 0.787234 (-8275 5950);
FORCEPROP 1 LAST MATERIAL EMPTY
J 0
(-8285 6025);
DISPLAY 0.787234 (-8285 6025);
FORCEPROP 1 LAST WATTAGE 1/20W
J 0
(-8285 6075);
DISPLAY 0.787234 (-8285 6075);
FORCEPROP 1 LAST VALUE 4.7K
J 0
(-8280 6175);
DISPLAY 0.787234 (-8280 6175);
FORCEPROP 2 LAST CDS_LIB pure_quanta
J 0
(-8325 6100);
DISPLAY INVISIBLE (-8325 6100);
FORCEPROP 1 LAST PATH I27
J 0
(-8275 6275);
DISPLAY 0.978723 (-8275 6275);
PAINT WHITE (-8275 6275);
DISPLAY INVISIBLE (-8275 6275);
FORCEPROP 1 LAST PART_NUMBER CS24701JE04
J 0
(-8285 5975);
DISPLAY 0.978723 (-8285 5975);
DISPLAY INVISIBLE (-8285 5975);
FORCEADD Q_RES..2
(-8950 6100);
FORCEPROP 1 LAST LOCATION R706
J 0
(-8905 6225);
DISPLAY 0.787234 (-8905 6225);
FORCEPROP 0 LAST $SEC 1
J 0
(-8900 6275);
DISPLAY 0.680851 (-8900 6275);
PAINT MONO (-8900 6275);
DISPLAY INVISIBLE (-8900 6275);
FORCEPROP 0 LAST CDS_SEC 1
J 0
(-8900 6275);
DISPLAY 0.680851 (-8900 6275);
DISPLAY INVISIBLE (-8900 6275);
FORCEPROP 1 LASTPIN (-8950 6200) $PN 1
J 0
(-8945 6162);
DISPLAY 0.787234 (-8945 6162);
PAINT MONO (-8945 6162);
FORCEPROP 1 LASTPIN (-8950 6000) $PN 2
J 0
(-8945 6010);
DISPLAY 0.787234 (-8945 6010);
PAINT MONO (-8945 6010);
FORCEPROP 1 LAST TOLERANCE 5%
J 0
(-8905 6125);
DISPLAY 0.787234 (-8905 6125);
FORCEPROP 1 LAST VALUE 4.7K
J 0
(-8905 6175);
DISPLAY 0.787234 (-8905 6175);
FORCEPROP 1 LAST WATTAGE 1/20W
J 0
(-8910 6075);
DISPLAY 0.787234 (-8910 6075);
FORCEPROP 1 LAST MATERIAL EMPTY
J 0
(-8910 6025);
DISPLAY 0.787234 (-8910 6025);
FORCEPROP 1 LAST PACK_TYPE 0201LF
J 0
(-8900 5950);
DISPLAY 0.787234 (-8900 5950);
FORCEPROP 2 LAST CDS_LIB pure_quanta
J 0
(-8950 6100);
DISPLAY INVISIBLE (-8950 6100);
FORCEPROP 1 LAST PATH I29
J 0
(-8900 6275);
DISPLAY 0.978723 (-8900 6275);
PAINT WHITE (-8900 6275);
DISPLAY INVISIBLE (-8900 6275);
FORCEPROP 1 LAST PART_NUMBER CS24701JE04
J 0
(-8910 5975);
DISPLAY 0.978723 (-8910 5975);
DISPLAY INVISIBLE (-8910 5975);
FORCEADD OFFPAGE..1
(-8050 1150);
FORCEPROP 2 LAST $XR0 183 
J 0
(-8332 1150);
DISPLAY 0.638298 (-8332 1150);
PAINT MONO (-8332 1150);
FORCEPROP 2 LAST CDS_LIB standard
J 0
(-8050 1150);
DISPLAY INVISIBLE (-8050 1150);
FORCEPROP 1 LAST OFFPAGE TRUE
J 0
(-7725 1025);
DISPLAY 0.872340 (-7725 1025);
DISPLAY INVISIBLE (-7725 1025);
FORCEPROP 1 LAST COMMENT_BODY TRUE
J 0
(-7925 1050);
DISPLAY 0.872340 (-7925 1050);
PAINT GREEN (-7925 1050);
DISPLAY INVISIBLE (-7925 1050);
FORCEPROP 2 LAST PATH I3
J 0
(-8000 1225);
DISPLAY 0.680851 (-8000 1225);
DISPLAY INVISIBLE (-8000 1225);
FORCEADD Q_RES..2
(-7725 5125);
FORCEPROP 1 LAST LOCATION R725
J 0
(-7680 5250);
DISPLAY 0.787234 (-7680 5250);
FORCEPROP 0 LAST $SEC 1
J 0
(-7675 5300);
DISPLAY 0.680851 (-7675 5300);
PAINT MONO (-7675 5300);
DISPLAY INVISIBLE (-7675 5300);
FORCEPROP 0 LAST CDS_SEC 1
J 0
(-7675 5300);
DISPLAY 0.680851 (-7675 5300);
DISPLAY INVISIBLE (-7675 5300);
FORCEPROP 1 LASTPIN (-7725 5225) $PN 1
J 0
(-7720 5187);
DISPLAY 0.787234 (-7720 5187);
PAINT MONO (-7720 5187);
FORCEPROP 1 LASTPIN (-7725 5025) $PN 2
J 0
(-7720 5035);
DISPLAY 0.787234 (-7720 5035);
PAINT MONO (-7720 5035);
FORCEPROP 1 LAST TOLERANCE 5%
J 0
(-7680 5150);
DISPLAY 0.787234 (-7680 5150);
FORCEPROP 1 LAST PACK_TYPE 0201LF
J 0
(-7685 4950);
DISPLAY 0.787234 (-7685 4950);
FORCEPROP 1 LAST VALUE 4.7K
J 0
(-7680 5200);
DISPLAY 0.787234 (-7680 5200);
FORCEPROP 1 LAST WATTAGE 1/20W
J 0
(-7685 5100);
DISPLAY 0.787234 (-7685 5100);
FORCEPROP 1 LAST MATERIAL CHIP
J 0
(-7685 5050);
DISPLAY 0.787234 (-7685 5050);
FORCEPROP 2 LAST CDS_LIB pure_quanta
J 0
(-7725 5125);
DISPLAY INVISIBLE (-7725 5125);
FORCEPROP 1 LAST PATH I32
J 0
(-7675 5300);
DISPLAY 0.978723 (-7675 5300);
PAINT WHITE (-7675 5300);
DISPLAY INVISIBLE (-7675 5300);
FORCEPROP 1 LAST PART_NUMBER CS24701JE04
J 0
(-7685 5000);
DISPLAY 0.787234 (-7685 5000);
DISPLAY INVISIBLE (-7685 5000);
FORCEADD Q_RES..2
(-8025 5125);
FORCEPROP 1 LAST LOCATION R723
J 0
(-7980 5250);
DISPLAY 0.787234 (-7980 5250);
FORCEPROP 0 LAST $SEC 1
J 0
(-7975 5300);
DISPLAY 0.680851 (-7975 5300);
PAINT MONO (-7975 5300);
DISPLAY INVISIBLE (-7975 5300);
FORCEPROP 0 LAST CDS_SEC 1
J 0
(-7975 5300);
DISPLAY 0.680851 (-7975 5300);
DISPLAY INVISIBLE (-7975 5300);
FORCEPROP 1 LASTPIN (-8025 5225) $PN 1
J 0
(-8020 5187);
DISPLAY 0.787234 (-8020 5187);
PAINT MONO (-8020 5187);
FORCEPROP 1 LASTPIN (-8025 5025) $PN 2
J 0
(-8020 5035);
DISPLAY 0.787234 (-8020 5035);
PAINT MONO (-8020 5035);
FORCEPROP 1 LAST TOLERANCE 5%
J 0
(-7980 5150);
DISPLAY 0.787234 (-7980 5150);
FORCEPROP 1 LAST PACK_TYPE 0201LF
J 0
(-7985 4950);
DISPLAY 0.787234 (-7985 4950);
FORCEPROP 1 LAST MATERIAL CHIP
J 0
(-7985 5050);
DISPLAY 0.787234 (-7985 5050);
FORCEPROP 1 LAST WATTAGE 1/20W
J 0
(-7985 5100);
DISPLAY 0.787234 (-7985 5100);
FORCEPROP 1 LAST VALUE 4.7K
J 0
(-7980 5200);
DISPLAY 0.787234 (-7980 5200);
FORCEPROP 2 LAST CDS_LIB pure_quanta
J 0
(-8025 5125);
DISPLAY INVISIBLE (-8025 5125);
FORCEPROP 1 LAST PATH I33
J 0
(-7975 5300);
DISPLAY 0.978723 (-7975 5300);
PAINT WHITE (-7975 5300);
DISPLAY INVISIBLE (-7975 5300);
FORCEPROP 1 LAST PART_NUMBER CS24701JE04
J 0
(-7985 5000);
DISPLAY 0.978723 (-7985 5000);
DISPLAY INVISIBLE (-7985 5000);
FORCEADD Q_RES..2
(-8325 5150);
FORCEPROP 1 LAST LOCATION R719
J 0
(-8280 5275);
DISPLAY 0.787234 (-8280 5275);
FORCEPROP 0 LAST $SEC 1
J 0
(-8275 5325);
DISPLAY 0.680851 (-8275 5325);
PAINT MONO (-8275 5325);
DISPLAY INVISIBLE (-8275 5325);
FORCEPROP 0 LAST CDS_SEC 1
J 0
(-8275 5325);
DISPLAY 0.680851 (-8275 5325);
DISPLAY INVISIBLE (-8275 5325);
FORCEPROP 1 LASTPIN (-8325 5250) $PN 1
J 0
(-8320 5212);
DISPLAY 0.787234 (-8320 5212);
PAINT MONO (-8320 5212);
FORCEPROP 1 LASTPIN (-8325 5050) $PN 2
J 0
(-8320 5060);
DISPLAY 0.787234 (-8320 5060);
PAINT MONO (-8320 5060);
FORCEPROP 1 LAST VALUE 4.7K
J 0
(-8280 5225);
DISPLAY 0.787234 (-8280 5225);
FORCEPROP 1 LAST TOLERANCE 5%
J 0
(-8280 5175);
DISPLAY 0.787234 (-8280 5175);
FORCEPROP 1 LAST WATTAGE 1/20W
J 0
(-8285 5125);
DISPLAY 0.787234 (-8285 5125);
FORCEPROP 1 LAST PACK_TYPE 0201LF
J 0
(-8285 4975);
DISPLAY 0.787234 (-8285 4975);
FORCEPROP 1 LAST MATERIAL CHIP
J 0
(-8285 5075);
DISPLAY 0.787234 (-8285 5075);
FORCEPROP 2 LAST CDS_LIB pure_quanta
J 0
(-8325 5150);
DISPLAY INVISIBLE (-8325 5150);
FORCEPROP 1 LAST PATH I34
J 0
(-8275 5325);
DISPLAY 0.978723 (-8275 5325);
PAINT WHITE (-8275 5325);
DISPLAY INVISIBLE (-8275 5325);
FORCEPROP 1 LAST PART_NUMBER CS24701JE04
J 0
(-8285 5025);
DISPLAY 0.978723 (-8285 5025);
DISPLAY INVISIBLE (-8285 5025);
FORCEADD Q_RES..2
(-8650 5150);
FORCEPROP 1 LAST LOCATION R715
J 0
(-8605 5275);
DISPLAY 0.787234 (-8605 5275);
FORCEPROP 0 LAST $SEC 1
J 0
(-8600 5325);
DISPLAY 0.680851 (-8600 5325);
PAINT MONO (-8600 5325);
DISPLAY INVISIBLE (-8600 5325);
FORCEPROP 0 LAST CDS_SEC 1
J 0
(-8600 5325);
DISPLAY 0.680851 (-8600 5325);
DISPLAY INVISIBLE (-8600 5325);
FORCEPROP 1 LASTPIN (-8650 5250) $PN 1
J 0
(-8645 5212);
DISPLAY 0.787234 (-8645 5212);
PAINT MONO (-8645 5212);
FORCEPROP 1 LASTPIN (-8650 5050) $PN 2
J 0
(-8645 5060);
DISPLAY 0.787234 (-8645 5060);
PAINT MONO (-8645 5060);
FORCEPROP 1 LAST VALUE 10K
J 0
(-8605 5225);
DISPLAY 0.787234 (-8605 5225);
FORCEPROP 1 LAST TOLERANCE 1%
J 0
(-8605 5175);
DISPLAY 0.787234 (-8605 5175);
FORCEPROP 1 LAST WATTAGE 1/20W
J 0
(-8610 5125);
DISPLAY 0.787234 (-8610 5125);
FORCEPROP 1 LAST MATERIAL CHIP
J 0
(-8610 5075);
DISPLAY 0.787234 (-8610 5075);
FORCEPROP 1 LAST PACK_TYPE 0201LF
J 0
(-8610 4975);
DISPLAY 0.787234 (-8610 4975);
FORCEPROP 2 LAST CDS_LIB pure_quanta
J 0
(-8650 5150);
DISPLAY INVISIBLE (-8650 5150);
FORCEPROP 1 LAST PATH I35
J 0
(-8600 5325);
DISPLAY 0.978723 (-8600 5325);
PAINT WHITE (-8600 5325);
DISPLAY INVISIBLE (-8600 5325);
FORCEPROP 1 LAST PART_NUMBER CS31001FE17
J 0
(-8610 5025);
DISPLAY 0.510638 (-8610 5025);
DISPLAY INVISIBLE (-8610 5025);
FORCEADD Q_RES..2
(-8950 5150);
FORCEPROP 1 LAST LOCATION R707
J 0
(-8905 5275);
DISPLAY 0.787234 (-8905 5275);
FORCEPROP 0 LAST $SEC 1
J 0
(-8900 5325);
DISPLAY 0.680851 (-8900 5325);
PAINT MONO (-8900 5325);
DISPLAY INVISIBLE (-8900 5325);
FORCEPROP 0 LAST CDS_SEC 1
J 0
(-8900 5325);
DISPLAY 0.680851 (-8900 5325);
DISPLAY INVISIBLE (-8900 5325);
FORCEPROP 1 LASTPIN (-8950 5250) $PN 1
J 0
(-8945 5212);
DISPLAY 0.787234 (-8945 5212);
PAINT MONO (-8945 5212);
FORCEPROP 1 LASTPIN (-8950 5050) $PN 2
J 0
(-8945 5060);
DISPLAY 0.787234 (-8945 5060);
PAINT MONO (-8945 5060);
FORCEPROP 1 LAST VALUE 10K
J 0
(-8905 5225);
DISPLAY 0.787234 (-8905 5225);
FORCEPROP 1 LAST TOLERANCE 1%
J 0
(-8905 5175);
DISPLAY 0.787234 (-8905 5175);
FORCEPROP 1 LAST WATTAGE 1/20W
J 0
(-8910 5125);
DISPLAY 0.787234 (-8910 5125);
FORCEPROP 1 LAST MATERIAL CHIP
J 0
(-8910 5075);
DISPLAY 0.787234 (-8910 5075);
FORCEPROP 1 LAST PACK_TYPE 0201LF
J 0
(-8910 4975);
DISPLAY 0.787234 (-8910 4975);
FORCEPROP 2 LAST CDS_LIB pure_quanta
J 0
(-8950 5150);
DISPLAY INVISIBLE (-8950 5150);
FORCEPROP 1 LAST PATH I36
J 0
(-8900 5325);
DISPLAY 0.978723 (-8900 5325);
PAINT WHITE (-8900 5325);
DISPLAY INVISIBLE (-8900 5325);
FORCEPROP 1 LAST PART_NUMBER CS31001FE17
J 0
(-8910 5025);
DISPLAY 0.638298 (-8910 5025);
DISPLAY INVISIBLE (-8910 5025);
FORCEADD P1V0..1
(-8950 6500);
FORCEPROP 3 LASTPIN (-8950 6450) SIG_NAME P1V8_CPU1_RT_1D\g
J 0
(-8940 6460);
DISPLAY 0.659574 (-8940 6460);
PAINT MONO (-8940 6460);
DISPLAY INVISIBLE (-8940 6460);
FORCEPROP 1 LAST HDL_POWER P1V8_CPU1_RT_1D
J 1
(-8950 6550);
DISPLAY 0.489362 (-8950 6550);
PAINT SKYBLUE (-8950 6550);
FORCEPROP 2 LAST CDS_LIB pure_quanta_power
J 0
(-8950 6500);
DISPLAY INVISIBLE (-8950 6500);
FORCEPROP 1 LAST PATH I39
J 0
(-8900 6525);
DISPLAY 0.872340 (-8900 6525);
PAINT AQUA (-8900 6525);
DISPLAY INVISIBLE (-8900 6525);
FORCEADD UNIVERSAL_GND..1
(-6150 500);
FORCEPROP 3 LASTPIN (-6150 550) SIG_NAME GND\g
J 0
(-6140 560);
DISPLAY 0.659574 (-6140 560);
PAINT MONO (-6140 560);
DISPLAY INVISIBLE (-6140 560);
FORCEPROP 2 LAST CDS_LIB pure_quanta_power
J 0
(-6150 500);
DISPLAY INVISIBLE (-6150 500);
FORCEPROP 1 LAST HDL_POWER GND
J 1
(-6125 425);
DISPLAY 0.872340 (-6125 425);
PAINT GREEN (-6125 425);
DISPLAY INVISIBLE (-6125 425);
FORCEPROP 1 LAST PATH I4
J 0
(-6075 500);
DISPLAY 0.872340 (-6075 500);
PAINT AQUA (-6075 500);
DISPLAY INVISIBLE (-6075 500);
FORCEADD UNIVERSAL_GND..1
(-7425 4650);
FORCEPROP 3 LASTPIN (-7425 4700) SIG_NAME GND\g
J 0
(-7415 4710);
DISPLAY 0.659574 (-7415 4710);
PAINT MONO (-7415 4710);
DISPLAY INVISIBLE (-7415 4710);
FORCEPROP 2 LAST CDS_LIB pure_quanta_power
J 0
(-7425 4650);
DISPLAY INVISIBLE (-7425 4650);
FORCEPROP 1 LAST HDL_POWER GND
J 1
(-7400 4575);
DISPLAY 0.872340 (-7400 4575);
PAINT GREEN (-7400 4575);
DISPLAY INVISIBLE (-7400 4575);
FORCEPROP 1 LAST PATH I40
J 0
(-7350 4650);
DISPLAY 0.872340 (-7350 4650);
PAINT AQUA (-7350 4650);
DISPLAY INVISIBLE (-7350 4650);
FORCEADD OFFPAGE..5
R 2
(-6375 5800);
FORCEPROP 2 LAST $XR0 321 
J 0
(-6186 5800);
DISPLAY 0.638298 (-6186 5800);
PAINT MONO (-6186 5800);
FORCEPROP 2 LAST CDS_LIB standard
J 0
(-6375 5800);
DISPLAY INVISIBLE (-6375 5800);
FORCEPROP 1 LAST OFFPAGE TRUE
J 2
(-6700 5675);
DISPLAY 0.872340 (-6700 5675);
PAINT GREEN (-6700 5675);
DISPLAY INVISIBLE (-6700 5675);
FORCEPROP 1 LAST COMMENT_BODY TRUE
J 2
(-6475 5725);
DISPLAY 0.872340 (-6475 5725);
PAINT GREEN (-6475 5725);
DISPLAY INVISIBLE (-6475 5725);
FORCEPROP 2 LAST PATH I43
J 0
(-6200 5875);
DISPLAY 0.680851 (-6200 5875);
DISPLAY INVISIBLE (-6200 5875);
FORCEADD OFFPAGE..5
R 2
(-6375 5725);
FORCEPROP 2 LAST $XR0 321 
J 0
(-6186 5725);
DISPLAY 0.638298 (-6186 5725);
PAINT MONO (-6186 5725);
FORCEPROP 2 LAST CDS_LIB standard
J 0
(-6375 5725);
DISPLAY INVISIBLE (-6375 5725);
FORCEPROP 1 LAST OFFPAGE TRUE
J 2
(-6700 5600);
DISPLAY 0.872340 (-6700 5600);
PAINT GREEN (-6700 5600);
DISPLAY INVISIBLE (-6700 5600);
FORCEPROP 1 LAST COMMENT_BODY TRUE
J 2
(-6475 5650);
DISPLAY 0.872340 (-6475 5650);
PAINT GREEN (-6475 5650);
DISPLAY INVISIBLE (-6475 5650);
FORCEPROP 2 LAST PATH I44
J 0
(-6200 5800);
DISPLAY 0.680851 (-6200 5800);
DISPLAY INVISIBLE (-6200 5800);
FORCEADD OFFPAGE..1
(-6150 2250);
FORCEPROP 2 LAST $XR0 321 
J 0
(-6402 2250);
DISPLAY 0.638298 (-6402 2250);
PAINT MONO (-6402 2250);
FORCEPROP 2 LAST CDS_LIB standard
J 0
(-6150 2250);
DISPLAY INVISIBLE (-6150 2250);
FORCEPROP 1 LAST OFFPAGE TRUE
J 0
(-5825 2125);
DISPLAY 0.872340 (-5825 2125);
DISPLAY INVISIBLE (-5825 2125);
FORCEPROP 1 LAST COMMENT_BODY TRUE
J 0
(-6025 2150);
DISPLAY 0.872340 (-6025 2150);
PAINT GREEN (-6025 2150);
DISPLAY INVISIBLE (-6025 2150);
FORCEPROP 2 LAST PATH I45
J 0
(-6100 2325);
DISPLAY 0.680851 (-6100 2325);
DISPLAY INVISIBLE (-6100 2325);
FORCEADD OFFPAGE..1
(-6150 2150);
FORCEPROP 2 LAST $XR0 321 
J 0
(-6402 2150);
DISPLAY 0.638298 (-6402 2150);
PAINT MONO (-6402 2150);
FORCEPROP 2 LAST CDS_LIB standard
J 0
(-6150 2150);
DISPLAY INVISIBLE (-6150 2150);
FORCEPROP 1 LAST OFFPAGE TRUE
J 0
(-5825 2025);
DISPLAY 0.872340 (-5825 2025);
DISPLAY INVISIBLE (-5825 2025);
FORCEPROP 1 LAST COMMENT_BODY TRUE
J 0
(-6025 2050);
DISPLAY 0.872340 (-6025 2050);
PAINT GREEN (-6025 2050);
DISPLAY INVISIBLE (-6025 2050);
FORCEPROP 2 LAST PATH I46
J 0
(-6100 2225);
DISPLAY 0.680851 (-6100 2225);
DISPLAY INVISIBLE (-6100 2225);
FORCEADD OFFPAGE..1
(-6150 2050);
FORCEPROP 2 LAST $XR0 321 
J 0
(-6402 2050);
DISPLAY 0.638298 (-6402 2050);
PAINT MONO (-6402 2050);
FORCEPROP 2 LAST CDS_LIB standard
J 0
(-6150 2050);
DISPLAY INVISIBLE (-6150 2050);
FORCEPROP 1 LAST OFFPAGE TRUE
J 0
(-5825 1925);
DISPLAY 0.872340 (-5825 1925);
DISPLAY INVISIBLE (-5825 1925);
FORCEPROP 1 LAST COMMENT_BODY TRUE
J 0
(-6025 1950);
DISPLAY 0.872340 (-6025 1950);
PAINT GREEN (-6025 1950);
DISPLAY INVISIBLE (-6025 1950);
FORCEPROP 2 LAST PATH I47
J 0
(-6100 2125);
DISPLAY 0.680851 (-6100 2125);
DISPLAY INVISIBLE (-6100 2125);
FORCEADD OFFPAGE..5
R 2
(-6375 5675);
FORCEPROP 2 LAST $XR0 321 
J 0
(-6186 5675);
DISPLAY 0.638298 (-6186 5675);
PAINT MONO (-6186 5675);
FORCEPROP 2 LAST CDS_LIB standard
J 0
(-6375 5675);
DISPLAY INVISIBLE (-6375 5675);
FORCEPROP 1 LAST OFFPAGE TRUE
J 2
(-6700 5550);
DISPLAY 0.872340 (-6700 5550);
PAINT GREEN (-6700 5550);
DISPLAY INVISIBLE (-6700 5550);
FORCEPROP 1 LAST COMMENT_BODY TRUE
J 2
(-6475 5600);
DISPLAY 0.872340 (-6475 5600);
PAINT GREEN (-6475 5600);
DISPLAY INVISIBLE (-6475 5600);
FORCEPROP 2 LAST PATH I48
J 0
(-6200 5750);
DISPLAY 0.680851 (-6200 5750);
DISPLAY INVISIBLE (-6200 5750);
FORCEADD OFFPAGE..5
R 2
(-6375 5625);
FORCEPROP 2 LAST $XR0 321 
J 0
(-6186 5625);
DISPLAY 0.638298 (-6186 5625);
PAINT MONO (-6186 5625);
FORCEPROP 2 LAST CDS_LIB standard
J 0
(-6375 5625);
DISPLAY INVISIBLE (-6375 5625);
FORCEPROP 1 LAST OFFPAGE TRUE
J 2
(-6700 5500);
DISPLAY 0.872340 (-6700 5500);
PAINT GREEN (-6700 5500);
DISPLAY INVISIBLE (-6700 5500);
FORCEPROP 1 LAST COMMENT_BODY TRUE
J 2
(-6475 5550);
DISPLAY 0.872340 (-6475 5550);
PAINT GREEN (-6475 5550);
DISPLAY INVISIBLE (-6475 5550);
FORCEPROP 2 LAST PATH I49
J 0
(-6200 5700);
DISPLAY 0.680851 (-6200 5700);
DISPLAY INVISIBLE (-6200 5700);
FORCEADD UNIVERSAL_GND..1
(-6300 500);
FORCEPROP 3 LASTPIN (-6300 550) SIG_NAME GND\g
J 0
(-6290 560);
DISPLAY 0.659574 (-6290 560);
PAINT MONO (-6290 560);
DISPLAY INVISIBLE (-6290 560);
FORCEPROP 2 LAST CDS_LIB pure_quanta_power
J 0
(-6300 500);
DISPLAY INVISIBLE (-6300 500);
FORCEPROP 1 LAST HDL_POWER GND
J 1
(-6275 425);
DISPLAY 0.872340 (-6275 425);
PAINT GREEN (-6275 425);
DISPLAY INVISIBLE (-6275 425);
FORCEPROP 1 LAST PATH I5
J 0
(-6225 500);
DISPLAY 0.872340 (-6225 500);
PAINT AQUA (-6225 500);
DISPLAY INVISIBLE (-6225 500);
FORCEADD OFFPAGE..5
R 2
(-6375 5575);
FORCEPROP 2 LAST $XR0 321 
J 0
(-6186 5575);
DISPLAY 0.638298 (-6186 5575);
PAINT MONO (-6186 5575);
FORCEPROP 2 LAST CDS_LIB standard
J 0
(-6375 5575);
DISPLAY INVISIBLE (-6375 5575);
FORCEPROP 1 LAST OFFPAGE TRUE
J 2
(-6700 5450);
DISPLAY 0.872340 (-6700 5450);
PAINT GREEN (-6700 5450);
DISPLAY INVISIBLE (-6700 5450);
FORCEPROP 1 LAST COMMENT_BODY TRUE
J 2
(-6475 5500);
DISPLAY 0.872340 (-6475 5500);
PAINT GREEN (-6475 5500);
DISPLAY INVISIBLE (-6475 5500);
FORCEPROP 2 LAST PATH I50
J 0
(-6200 5650);
DISPLAY 0.680851 (-6200 5650);
DISPLAY INVISIBLE (-6200 5650);
FORCEADD OFFPAGE..1
R 2
(-2400 2900);
FORCEPROP 2 LAST $XR0 321 
J 0
(-2214 2900);
DISPLAY 0.638298 (-2214 2900);
PAINT MONO (-2214 2900);
FORCEPROP 2 LAST CDS_LIB standard
J 2
(-2400 2900);
DISPLAY INVISIBLE (-2400 2900);
FORCEPROP 1 LAST OFFPAGE TRUE
J 2
(-2725 2775);
DISPLAY 0.872340 (-2725 2775);
DISPLAY INVISIBLE (-2725 2775);
FORCEPROP 1 LAST COMMENT_BODY TRUE
J 2
(-2525 2800);
DISPLAY 0.872340 (-2525 2800);
PAINT GREEN (-2525 2800);
DISPLAY INVISIBLE (-2525 2800);
FORCEPROP 2 LAST PATH I53
J 2
(-2450 2975);
DISPLAY 0.680851 (-2450 2975);
DISPLAY INVISIBLE (-2450 2975);
FORCEADD Q_RES..2
(-5025 6175);
FORCEPROP 1 LAST LOCATION R727
J 0
(-4980 6300);
DISPLAY 0.787234 (-4980 6300);
FORCEPROP 0 LAST $SEC 1
J 0
(-4975 6350);
DISPLAY 0.680851 (-4975 6350);
PAINT MONO (-4975 6350);
DISPLAY INVISIBLE (-4975 6350);
FORCEPROP 0 LAST CDS_SEC 1
J 0
(-4975 6350);
DISPLAY 0.680851 (-4975 6350);
DISPLAY INVISIBLE (-4975 6350);
FORCEPROP 1 LASTPIN (-5025 6275) $PN 1
J 0
(-5020 6237);
DISPLAY 0.787234 (-5020 6237);
PAINT MONO (-5020 6237);
FORCEPROP 1 LASTPIN (-5025 6075) $PN 2
J 0
(-5020 6085);
DISPLAY 0.787234 (-5020 6085);
PAINT MONO (-5020 6085);
FORCEPROP 1 LAST VALUE 4.7K
J 0
(-4980 6250);
DISPLAY 0.787234 (-4980 6250);
FORCEPROP 1 LAST TOLERANCE 5%
J 0
(-4980 6200);
DISPLAY 0.787234 (-4980 6200);
FORCEPROP 1 LAST MATERIAL CHIP
J 0
(-4985 6100);
DISPLAY 0.787234 (-4985 6100);
FORCEPROP 1 LAST WATTAGE 1/20W
J 0
(-4985 6150);
DISPLAY 0.787234 (-4985 6150);
FORCEPROP 1 LAST PACK_TYPE 0201LF
J 0
(-4985 6000);
DISPLAY 0.787234 (-4985 6000);
FORCEPROP 2 LAST CDS_LIB pure_quanta
J 0
(-5025 6175);
DISPLAY INVISIBLE (-5025 6175);
FORCEPROP 1 LAST PATH I54
J 0
(-4975 6350);
DISPLAY 0.978723 (-4975 6350);
PAINT WHITE (-4975 6350);
DISPLAY INVISIBLE (-4975 6350);
FORCEPROP 1 LAST PART_NUMBER CS24701JE04
J 0
(-4985 6050);
DISPLAY 0.787234 (-4985 6050);
DISPLAY INVISIBLE (-4985 6050);
FORCEADD Q_RES..2
(-5025 5650);
FORCEPROP 1 LAST LOCATION R728
J 0
(-4980 5775);
DISPLAY 0.787234 (-4980 5775);
FORCEPROP 0 LAST $SEC 1
J 0
(-4975 5825);
DISPLAY 0.680851 (-4975 5825);
PAINT MONO (-4975 5825);
DISPLAY INVISIBLE (-4975 5825);
FORCEPROP 0 LAST CDS_SEC 1
J 0
(-4975 5825);
DISPLAY 0.680851 (-4975 5825);
DISPLAY INVISIBLE (-4975 5825);
FORCEPROP 1 LASTPIN (-5025 5750) $PN 1
J 0
(-5020 5712);
DISPLAY 0.787234 (-5020 5712);
PAINT MONO (-5020 5712);
FORCEPROP 1 LASTPIN (-5025 5550) $PN 2
J 0
(-5020 5560);
DISPLAY 0.787234 (-5020 5560);
PAINT MONO (-5020 5560);
FORCEPROP 1 LAST WATTAGE 1/20W
J 0
(-4985 5625);
DISPLAY 0.787234 (-4985 5625);
FORCEPROP 1 LAST TOLERANCE 5%
J 0
(-4980 5675);
DISPLAY 0.787234 (-4980 5675);
FORCEPROP 1 LAST VALUE 4.7K
J 0
(-4980 5725);
DISPLAY 0.787234 (-4980 5725);
FORCEPROP 1 LAST MATERIAL EMPTY
J 0
(-4985 5575);
DISPLAY 0.787234 (-4985 5575);
FORCEPROP 1 LAST PACK_TYPE 0201LF
J 0
(-4985 5475);
DISPLAY 0.787234 (-4985 5475);
FORCEPROP 2 LAST CDS_LIB pure_quanta
J 0
(-5025 5650);
DISPLAY INVISIBLE (-5025 5650);
FORCEPROP 1 LAST PATH I55
J 0
(-4975 5825);
DISPLAY 0.978723 (-4975 5825);
PAINT WHITE (-4975 5825);
DISPLAY INVISIBLE (-4975 5825);
FORCEPROP 1 LAST PART_NUMBER CS24701JE04
J 0
(-4985 5525);
DISPLAY 0.787234 (-4985 5525);
DISPLAY INVISIBLE (-4985 5525);
FORCEADD P1V0..1
(-5025 6500);
FORCEPROP 3 LASTPIN (-5025 6450) SIG_NAME P1V8_CPU1_RT_1D\g
J 0
(-5015 6460);
DISPLAY 0.659574 (-5015 6460);
PAINT MONO (-5015 6460);
DISPLAY INVISIBLE (-5015 6460);
FORCEPROP 1 LAST HDL_POWER P1V8_CPU1_RT_1D
J 1
(-5025 6550);
DISPLAY 0.489362 (-5025 6550);
PAINT SKYBLUE (-5025 6550);
FORCEPROP 2 LAST CDS_LIB pure_quanta_power
J 0
(-5025 6500);
DISPLAY INVISIBLE (-5025 6500);
FORCEPROP 1 LAST PATH I56
J 0
(-4975 6525);
DISPLAY 0.872340 (-4975 6525);
PAINT AQUA (-4975 6525);
DISPLAY INVISIBLE (-4975 6525);
FORCEADD UNIVERSAL_GND..1
(-5025 5300);
FORCEPROP 3 LASTPIN (-5025 5350) SIG_NAME GND\g
J 0
(-5015 5360);
DISPLAY 0.659574 (-5015 5360);
PAINT MONO (-5015 5360);
DISPLAY INVISIBLE (-5015 5360);
FORCEPROP 2 LAST CDS_LIB pure_quanta_power
J 0
(-5025 5300);
DISPLAY INVISIBLE (-5025 5300);
FORCEPROP 1 LAST HDL_POWER GND
J 1
(-5000 5225);
DISPLAY 0.872340 (-5000 5225);
PAINT GREEN (-5000 5225);
DISPLAY INVISIBLE (-5000 5225);
FORCEPROP 1 LAST PATH I57
J 0
(-4950 5300);
DISPLAY 0.872340 (-4950 5300);
PAINT AQUA (-4950 5300);
DISPLAY INVISIBLE (-4950 5300);
FORCEADD OFFPAGE..5
R 2
(-4150 5900);
FORCEPROP 2 LAST $XR0 321 
J 0
(-3961 5900);
DISPLAY 0.638298 (-3961 5900);
PAINT MONO (-3961 5900);
FORCEPROP 2 LAST CDS_LIB standard
J 0
(-4150 5900);
DISPLAY INVISIBLE (-4150 5900);
FORCEPROP 1 LAST OFFPAGE TRUE
J 2
(-4475 5775);
DISPLAY 0.872340 (-4475 5775);
PAINT GREEN (-4475 5775);
DISPLAY INVISIBLE (-4475 5775);
FORCEPROP 1 LAST COMMENT_BODY TRUE
J 2
(-4250 5825);
DISPLAY 0.872340 (-4250 5825);
PAINT GREEN (-4250 5825);
DISPLAY INVISIBLE (-4250 5825);
FORCEPROP 2 LAST PATH I58
J 0
(-3975 5975);
DISPLAY 0.680851 (-3975 5975);
DISPLAY INVISIBLE (-3975 5975);
FORCEADD Q_RES..1
(-2575 2300);
FORCEPROP 1 LAST LOCATION R6708
J 0
(-2850 2300);
DISPLAY 0.978723 (-2850 2300);
FORCEPROP 2 LAST SEC 1
J 0
(-2625 2500);
DISPLAY 0.680851 (-2625 2500);
PAINT MONO (-2625 2500);
DISPLAY INVISIBLE (-2625 2500);
FORCEPROP 1 LASTPIN (-2675 2300) $PN 1
J 0
(-2663 2312);
DISPLAY 0.787234 (-2663 2312);
PAINT MONO (-2663 2312);
FORCEPROP 1 LASTPIN (-2475 2300) $PN 2
J 0
(-2513 2312);
DISPLAY 0.787234 (-2513 2312);
PAINT MONO (-2513 2312);
FORCEPROP 1 LAST PACK_TYPE 0201LF
J 0
(-2275 2300);
DISPLAY 0.787234 (-2275 2300);
FORCEPROP 1 LAST VALUE 0
J 2
(-2375 2300);
DISPLAY 0.787234 (-2375 2300);
FORCEPROP 1 LAST WATTAGE 1/20W
J 2
(-2775 2375);
DISPLAY 0.787234 (-2775 2375);
DISPLAY INVISIBLE (-2775 2375);
FORCEPROP 1 LAST TOLERANCE 5%
J 0
(-2750 2425);
DISPLAY 0.787234 (-2750 2425);
DISPLAY INVISIBLE (-2750 2425);
FORCEPROP 1 LAST MATERIAL CHIP
J 0
(-2750 2375);
DISPLAY 0.787234 (-2750 2375);
DISPLAY INVISIBLE (-2750 2375);
FORCEPROP 2 LAST SEC_TYPE 0201LF
J 0
(-2625 2500);
DISPLAY 0.680851 (-2625 2500);
DISPLAY INVISIBLE (-2625 2500);
FORCEPROP 2 LAST CDS_LIB pure_quanta
J 0
(-2575 2300);
DISPLAY INVISIBLE (-2575 2300);
FORCEPROP 1 LAST PATH I62
J 0
(-2625 2450);
DISPLAY 0.978723 (-2625 2450);
PAINT WHITE (-2625 2450);
DISPLAY INVISIBLE (-2625 2450);
FORCEPROP 1 LAST PART_NUMBER CS00001JE10
J 0
(-2625 2425);
DISPLAY 0.808511 (-2625 2425);
DISPLAY INVISIBLE (-2625 2425);
FORCEADD OFFPAGE..1
R 2
(-1050 2300);
FORCEPROP 2 LAST $XR0 81 
J 0
(-864 2300);
DISPLAY 0.638298 (-864 2300);
PAINT MONO (-864 2300);
FORCEPROP 2 LAST $XR1 321 
J 0
(-774 2300);
DISPLAY 0.638298 (-774 2300);
PAINT MONO (-774 2300);
FORCEPROP 2 LAST CDS_LIB standard
J 0
(-1050 2300);
DISPLAY INVISIBLE (-1050 2300);
FORCEPROP 1 LAST OFFPAGE TRUE
J 2
(-1375 2175);
DISPLAY 0.872340 (-1375 2175);
DISPLAY INVISIBLE (-1375 2175);
FORCEPROP 1 LAST COMMENT_BODY TRUE
J 2
(-1175 2200);
DISPLAY 0.872340 (-1175 2200);
PAINT GREEN (-1175 2200);
DISPLAY INVISIBLE (-1175 2200);
FORCEPROP 2 LAST PATH I63
J 0
(-875 2375);
DISPLAY 0.680851 (-875 2375);
DISPLAY INVISIBLE (-875 2375);
FORCEADD OFFPAGE..1
R 2
(-1050 2200);
FORCEPROP 2 LAST $XR0 81 
J 0
(-864 2200);
DISPLAY 0.638298 (-864 2200);
PAINT MONO (-864 2200);
FORCEPROP 2 LAST $XR1 321 
J 0
(-774 2200);
DISPLAY 0.638298 (-774 2200);
PAINT MONO (-774 2200);
FORCEPROP 2 LAST CDS_LIB standard
J 0
(-1050 2200);
DISPLAY INVISIBLE (-1050 2200);
FORCEPROP 1 LAST OFFPAGE TRUE
J 2
(-1375 2075);
DISPLAY 0.872340 (-1375 2075);
DISPLAY INVISIBLE (-1375 2075);
FORCEPROP 1 LAST COMMENT_BODY TRUE
J 2
(-1175 2100);
DISPLAY 0.872340 (-1175 2100);
PAINT GREEN (-1175 2100);
DISPLAY INVISIBLE (-1175 2100);
FORCEPROP 2 LAST PATH I64
J 0
(-875 2275);
DISPLAY 0.680851 (-875 2275);
DISPLAY INVISIBLE (-875 2275);
FORCEADD Q_RES..1
(-2575 2200);
FORCEPROP 1 LAST LOCATION R6709
J 0
(-2850 2200);
DISPLAY 0.978723 (-2850 2200);
FORCEPROP 0 LAST $SEC 1
J 0
(-2275 2250);
DISPLAY 0.680851 (-2275 2250);
PAINT MONO (-2275 2250);
DISPLAY INVISIBLE (-2275 2250);
FORCEPROP 0 LAST CDS_SEC 1
J 0
(-2275 2250);
DISPLAY 0.680851 (-2275 2250);
DISPLAY INVISIBLE (-2275 2250);
FORCEPROP 1 LASTPIN (-2675 2200) $PN 1
J 0
(-2663 2212);
DISPLAY 0.787234 (-2663 2212);
PAINT MONO (-2663 2212);
FORCEPROP 1 LASTPIN (-2475 2200) $PN 2
J 0
(-2513 2212);
DISPLAY 0.787234 (-2513 2212);
PAINT MONO (-2513 2212);
FORCEPROP 1 LAST PACK_TYPE 0201LF
J 0
(-2275 2200);
DISPLAY 0.787234 (-2275 2200);
FORCEPROP 1 LAST VALUE 0
J 2
(-2375 2200);
DISPLAY 0.787234 (-2375 2200);
FORCEPROP 2 LAST CDS_LIB pure_quanta
J 0
(-2575 2200);
DISPLAY INVISIBLE (-2575 2200);
FORCEPROP 1 LAST MATERIAL CHIP
J 0
(-2750 2275);
DISPLAY 0.787234 (-2750 2275);
DISPLAY INVISIBLE (-2750 2275);
FORCEPROP 1 LAST TOLERANCE 5%
J 0
(-2750 2325);
DISPLAY 0.787234 (-2750 2325);
DISPLAY INVISIBLE (-2750 2325);
FORCEPROP 1 LAST WATTAGE 1/20W
J 2
(-2775 2275);
DISPLAY 0.787234 (-2775 2275);
DISPLAY INVISIBLE (-2775 2275);
FORCEPROP 1 LAST PATH I65
J 0
(-2625 2350);
DISPLAY 0.978723 (-2625 2350);
PAINT WHITE (-2625 2350);
DISPLAY INVISIBLE (-2625 2350);
FORCEPROP 1 LAST PART_NUMBER CS00001JE10
J 0
(-2625 2325);
DISPLAY 0.808511 (-2625 2325);
DISPLAY INVISIBLE (-2625 2325);
FORCEADD UNIVERSAL_GND..1
(-3475 4900);
FORCEPROP 3 LASTPIN (-3475 4950) SIG_NAME GND\g
J 0
(-3465 4960);
DISPLAY 0.659574 (-3465 4960);
PAINT MONO (-3465 4960);
DISPLAY INVISIBLE (-3465 4960);
FORCEPROP 2 LAST CDS_LIB pure_quanta_power
J 0
(-3475 4900);
DISPLAY INVISIBLE (-3475 4900);
FORCEPROP 1 LAST HDL_POWER GND
J 1
(-3450 4825);
DISPLAY 0.872340 (-3450 4825);
PAINT GREEN (-3450 4825);
DISPLAY INVISIBLE (-3450 4825);
FORCEPROP 1 LAST PATH I72
J 0
(-3400 4900);
DISPLAY 0.872340 (-3400 4900);
PAINT AQUA (-3400 4900);
DISPLAY INVISIBLE (-3400 4900);
FORCEADD P1V0..1
(-3475 6525);
FORCEPROP 3 LASTPIN (-3475 6475) SIG_NAME P1V8_CPU1_RT_1D\g
J 0
(-3465 6485);
DISPLAY 0.659574 (-3465 6485);
PAINT MONO (-3465 6485);
DISPLAY INVISIBLE (-3465 6485);
FORCEPROP 1 LAST HDL_POWER P1V8_CPU1_RT_1D
J 1
(-3475 6575);
DISPLAY 0.489362 (-3475 6575);
PAINT SKYBLUE (-3475 6575);
FORCEPROP 2 LAST CDS_LIB pure_quanta_power
J 0
(-3475 6525);
DISPLAY INVISIBLE (-3475 6525);
FORCEPROP 1 LAST PATH I73
J 0
(-3425 6550);
DISPLAY 0.872340 (-3425 6550);
PAINT AQUA (-3425 6550);
DISPLAY INVISIBLE (-3425 6550);
FORCEADD OFFPAGE..1
(-5975 2750);
FORCEPROP 2 LAST $XR0 321 
J 0
(-6227 2750);
DISPLAY 0.638298 (-6227 2750);
PAINT MONO (-6227 2750);
FORCEPROP 2 LAST CDS_LIB standard
J 0
(-5975 2750);
DISPLAY INVISIBLE (-5975 2750);
FORCEPROP 1 LAST OFFPAGE TRUE
J 0
(-5650 2625);
DISPLAY 0.872340 (-5650 2625);
DISPLAY INVISIBLE (-5650 2625);
FORCEPROP 1 LAST COMMENT_BODY TRUE
J 0
(-5850 2650);
DISPLAY 0.872340 (-5850 2650);
PAINT GREEN (-5850 2650);
DISPLAY INVISIBLE (-5850 2650);
FORCEPROP 2 LAST PATH I74
J 0
(-5925 2825);
DISPLAY 0.680851 (-5925 2825);
DISPLAY INVISIBLE (-5925 2825);
FORCEADD OFFPAGE..1
(-5975 2650);
FORCEPROP 2 LAST $XR0 321 
J 0
(-6227 2650);
DISPLAY 0.638298 (-6227 2650);
PAINT MONO (-6227 2650);
FORCEPROP 2 LAST CDS_LIB standard
J 0
(-5975 2650);
DISPLAY INVISIBLE (-5975 2650);
FORCEPROP 1 LAST OFFPAGE TRUE
J 0
(-5650 2525);
DISPLAY 0.872340 (-5650 2525);
DISPLAY INVISIBLE (-5650 2525);
FORCEPROP 1 LAST COMMENT_BODY TRUE
J 0
(-5850 2550);
DISPLAY 0.872340 (-5850 2550);
PAINT GREEN (-5850 2550);
DISPLAY INVISIBLE (-5850 2550);
FORCEPROP 2 LAST PATH I75
J 0
(-5925 2725);
DISPLAY 0.680851 (-5925 2725);
DISPLAY INVISIBLE (-5925 2725);
FORCEADD OFFPAGE..1
(-5975 2550);
FORCEPROP 2 LAST $XR0 321 
J 0
(-6227 2550);
DISPLAY 0.638298 (-6227 2550);
PAINT MONO (-6227 2550);
FORCEPROP 2 LAST CDS_LIB standard
J 0
(-5975 2550);
DISPLAY INVISIBLE (-5975 2550);
FORCEPROP 1 LAST OFFPAGE TRUE
J 0
(-5650 2425);
DISPLAY 0.872340 (-5650 2425);
DISPLAY INVISIBLE (-5650 2425);
FORCEPROP 1 LAST COMMENT_BODY TRUE
J 0
(-5850 2450);
DISPLAY 0.872340 (-5850 2450);
PAINT GREEN (-5850 2450);
DISPLAY INVISIBLE (-5850 2450);
FORCEPROP 2 LAST PATH I76
J 0
(-5925 2625);
DISPLAY 0.680851 (-5925 2625);
DISPLAY INVISIBLE (-5925 2625);
FORCEADD OFFPAGE..5
R 2
(-1925 5775);
FORCEPROP 2 LAST $XR0 321 
J 0
(-1736 5775);
DISPLAY 0.638298 (-1736 5775);
PAINT MONO (-1736 5775);
FORCEPROP 2 LAST CDS_LIB standard
J 0
(-1925 5775);
DISPLAY INVISIBLE (-1925 5775);
FORCEPROP 1 LAST OFFPAGE TRUE
J 2
(-2250 5650);
DISPLAY 0.872340 (-2250 5650);
PAINT GREEN (-2250 5650);
DISPLAY INVISIBLE (-2250 5650);
FORCEPROP 1 LAST COMMENT_BODY TRUE
J 2
(-2025 5700);
DISPLAY 0.872340 (-2025 5700);
PAINT GREEN (-2025 5700);
DISPLAY INVISIBLE (-2025 5700);
FORCEPROP 2 LAST PATH I77
J 0
(-1750 5850);
DISPLAY 0.680851 (-1750 5850);
DISPLAY INVISIBLE (-1750 5850);
FORCEADD OFFPAGE..5
R 2
(-1925 5675);
FORCEPROP 2 LAST $XR0 321 
J 0
(-1736 5675);
DISPLAY 0.638298 (-1736 5675);
PAINT MONO (-1736 5675);
FORCEPROP 2 LAST CDS_LIB standard
J 0
(-1925 5675);
DISPLAY INVISIBLE (-1925 5675);
FORCEPROP 1 LAST OFFPAGE TRUE
J 2
(-2250 5550);
DISPLAY 0.872340 (-2250 5550);
PAINT GREEN (-2250 5550);
DISPLAY INVISIBLE (-2250 5550);
FORCEPROP 1 LAST COMMENT_BODY TRUE
J 2
(-2025 5600);
DISPLAY 0.872340 (-2025 5600);
PAINT GREEN (-2025 5600);
DISPLAY INVISIBLE (-2025 5600);
FORCEPROP 2 LAST PATH I78
J 0
(-1750 5750);
DISPLAY 0.680851 (-1750 5750);
DISPLAY INVISIBLE (-1750 5750);
FORCEADD OFFPAGE..5
R 2
(-1925 5575);
FORCEPROP 2 LAST $XR0 321 
J 0
(-1736 5575);
DISPLAY 0.638298 (-1736 5575);
PAINT MONO (-1736 5575);
FORCEPROP 2 LAST CDS_LIB standard
J 0
(-1925 5575);
DISPLAY INVISIBLE (-1925 5575);
FORCEPROP 1 LAST OFFPAGE TRUE
J 2
(-2250 5450);
DISPLAY 0.872340 (-2250 5450);
PAINT GREEN (-2250 5450);
DISPLAY INVISIBLE (-2250 5450);
FORCEPROP 1 LAST COMMENT_BODY TRUE
J 2
(-2025 5500);
DISPLAY 0.872340 (-2025 5500);
PAINT GREEN (-2025 5500);
DISPLAY INVISIBLE (-2025 5500);
FORCEPROP 2 LAST PATH I79
J 0
(-1750 5650);
DISPLAY 0.680851 (-1750 5650);
DISPLAY INVISIBLE (-1750 5650);
FORCEADD Q_RES..1
(-6600 1150);
FORCEPROP 1 LAST LOCATION R609
J 0
(-6850 1150);
DISPLAY 0.978723 (-6850 1150);
FORCEPROP 2 LAST SEC 1
J 0
(-6650 1350);
DISPLAY 0.680851 (-6650 1350);
PAINT MONO (-6650 1350);
DISPLAY INVISIBLE (-6650 1350);
FORCEPROP 1 LASTPIN (-6700 1150) $PN 1
J 0
(-6688 1162);
DISPLAY 0.787234 (-6688 1162);
PAINT MONO (-6688 1162);
FORCEPROP 1 LASTPIN (-6500 1150) $PN 2
J 0
(-6538 1162);
DISPLAY 0.787234 (-6538 1162);
PAINT MONO (-6538 1162);
FORCEPROP 1 LAST MATERIAL CHIP
J 0
(-6775 1225);
DISPLAY 0.787234 (-6775 1225);
FORCEPROP 1 LAST PACK_TYPE 0201LF
J 0
(-6575 1225);
DISPLAY 0.787234 (-6575 1225);
FORCEPROP 2 LAST CDS_LIB pure_quanta
J 0
(-6600 1150);
DISPLAY INVISIBLE (-6600 1150);
FORCEPROP 1 LAST TOLERANCE 5%
J 0
(-6775 1275);
DISPLAY 0.787234 (-6775 1275);
DISPLAY INVISIBLE (-6775 1275);
FORCEPROP 1 LAST VALUE 0
J 2
(-6800 1275);
DISPLAY 0.787234 (-6800 1275);
DISPLAY INVISIBLE (-6800 1275);
FORCEPROP 1 LAST WATTAGE 1/20W
J 2
(-6800 1225);
DISPLAY 0.787234 (-6800 1225);
DISPLAY INVISIBLE (-6800 1225);
FORCEPROP 2 LAST SEC_TYPE 0201LF
J 0
(-6650 1350);
DISPLAY 0.680851 (-6650 1350);
DISPLAY INVISIBLE (-6650 1350);
FORCEPROP 1 LAST PATH I8
J 0
(-6650 1300);
DISPLAY 0.978723 (-6650 1300);
PAINT WHITE (-6650 1300);
DISPLAY INVISIBLE (-6650 1300);
FORCEPROP 1 LAST PART_NUMBER CS00001JE10
J 0
(-6650 1275);
DISPLAY 0.808511 (-6650 1275);
DISPLAY INVISIBLE (-6650 1275);
FORCEADD OFFPAGE..1
R 2
(-2375 2700);
FORCEPROP 2 LAST $XR0 321 
J 0
(-2189 2700);
DISPLAY 0.638298 (-2189 2700);
PAINT MONO (-2189 2700);
FORCEPROP 2 LAST CDS_LIB standard
J 0
(-2375 2700);
DISPLAY INVISIBLE (-2375 2700);
FORCEPROP 1 LAST OFFPAGE TRUE
J 2
(-2700 2575);
DISPLAY 0.872340 (-2700 2575);
DISPLAY INVISIBLE (-2700 2575);
FORCEPROP 1 LAST COMMENT_BODY TRUE
J 2
(-2500 2600);
DISPLAY 0.872340 (-2500 2600);
PAINT GREEN (-2500 2600);
DISPLAY INVISIBLE (-2500 2600);
FORCEPROP 2 LAST PATH I83
J 0
(-2200 2775);
DISPLAY 0.680851 (-2200 2775);
DISPLAY INVISIBLE (-2200 2775);
FORCEADD Q_RES..2
(-8975 4225);
FORCEPROP 1 LAST LOCATION R6722
J 0
(-8930 4350);
DISPLAY 0.787234 (-8930 4350);
FORCEPROP 0 LAST $SEC 1
J 0
(-8925 4400);
DISPLAY 0.680851 (-8925 4400);
PAINT MONO (-8925 4400);
DISPLAY INVISIBLE (-8925 4400);
FORCEPROP 0 LAST CDS_SEC 1
J 0
(-8925 4400);
DISPLAY 0.680851 (-8925 4400);
DISPLAY INVISIBLE (-8925 4400);
FORCEPROP 1 LASTPIN (-8975 4325) $PN 1
J 0
(-8970 4287);
DISPLAY 0.787234 (-8970 4287);
PAINT MONO (-8970 4287);
FORCEPROP 1 LASTPIN (-8975 4125) $PN 2
J 0
(-8970 4135);
DISPLAY 0.787234 (-8970 4135);
PAINT MONO (-8970 4135);
FORCEPROP 1 LAST PACK_TYPE 0201LF
J 0
(-8925 4075);
DISPLAY 0.787234 (-8925 4075);
FORCEPROP 1 LAST WATTAGE 1/20W
J 0
(-8935 4200);
DISPLAY 0.787234 (-8935 4200);
FORCEPROP 1 LAST MATERIAL EMPTY
J 0
(-8935 4150);
DISPLAY 0.787234 (-8935 4150);
FORCEPROP 1 LAST VALUE 4.7K
J 0
(-8930 4300);
DISPLAY 0.787234 (-8930 4300);
FORCEPROP 1 LAST TOLERANCE 5%
J 0
(-8930 4250);
DISPLAY 0.787234 (-8930 4250);
FORCEPROP 2 LAST CDS_LIB pure_quanta
J 0
(-8975 4225);
DISPLAY INVISIBLE (-8975 4225);
FORCEPROP 1 LAST PATH I85
J 0
(-8925 4400);
DISPLAY 0.978723 (-8925 4400);
PAINT WHITE (-8925 4400);
DISPLAY INVISIBLE (-8925 4400);
FORCEPROP 1 LAST PART_NUMBER CS24701JE04
J 0
(-8935 4100);
DISPLAY 0.978723 (-8935 4100);
DISPLAY INVISIBLE (-8935 4100);
FORCEADD UNIVERSAL_GND..1
(-8975 3275);
FORCEPROP 3 LASTPIN (-8975 3325) SIG_NAME GND\g
J 0
(-8965 3335);
DISPLAY 0.659574 (-8965 3335);
PAINT MONO (-8965 3335);
DISPLAY INVISIBLE (-8965 3335);
FORCEPROP 2 LAST CDS_LIB pure_quanta_power
J 0
(-8975 3275);
DISPLAY INVISIBLE (-8975 3275);
FORCEPROP 1 LAST HDL_POWER GND
J 1
(-8950 3200);
DISPLAY 0.872340 (-8950 3200);
PAINT GREEN (-8950 3200);
DISPLAY INVISIBLE (-8950 3200);
FORCEPROP 1 LAST PATH I86
J 0
(-8900 3275);
DISPLAY 0.872340 (-8900 3275);
PAINT AQUA (-8900 3275);
DISPLAY INVISIBLE (-8900 3275);
FORCEADD P1V0..1
(-8975 4550);
FORCEPROP 3 LASTPIN (-8975 4500) SIG_NAME P1V8_CPU1_RT_1D\g
J 0
(-8965 4510);
DISPLAY 0.659574 (-8965 4510);
PAINT MONO (-8965 4510);
DISPLAY INVISIBLE (-8965 4510);
FORCEPROP 1 LAST HDL_POWER P1V8_CPU1_RT_1D
J 1
(-8975 4600);
DISPLAY 0.489362 (-8975 4600);
PAINT SKYBLUE (-8975 4600);
FORCEPROP 2 LAST CDS_LIB pure_quanta_power
J 0
(-8975 4550);
DISPLAY INVISIBLE (-8975 4550);
FORCEPROP 1 LAST PATH I87
J 0
(-8925 4575);
DISPLAY 0.872340 (-8925 4575);
PAINT AQUA (-8925 4575);
DISPLAY INVISIBLE (-8925 4575);
FORCEADD OFFPAGE..5
R 2
(-7800 4000);
FORCEPROP 2 LAST $XR0 321 
J 0
(-7611 4000);
DISPLAY 0.638298 (-7611 4000);
PAINT MONO (-7611 4000);
FORCEPROP 2 LAST CDS_LIB standard
J 0
(-7800 4000);
DISPLAY INVISIBLE (-7800 4000);
FORCEPROP 1 LAST OFFPAGE TRUE
J 2
(-8125 3875);
DISPLAY 0.872340 (-8125 3875);
PAINT GREEN (-8125 3875);
DISPLAY INVISIBLE (-8125 3875);
FORCEPROP 1 LAST COMMENT_BODY TRUE
J 2
(-7900 3925);
DISPLAY 0.872340 (-7900 3925);
PAINT GREEN (-7900 3925);
DISPLAY INVISIBLE (-7900 3925);
FORCEPROP 2 LAST PATH I88
J 0
(-7625 4075);
DISPLAY 0.680851 (-7625 4075);
DISPLAY INVISIBLE (-7625 4075);
FORCEADD OFFPAGE..5
R 2
(-6375 5500);
FORCEPROP 2 LAST $XR0 321 
J 0
(-6186 5500);
DISPLAY 0.638298 (-6186 5500);
PAINT MONO (-6186 5500);
FORCEPROP 2 LAST CDS_LIB standard
J 0
(-6375 5500);
DISPLAY INVISIBLE (-6375 5500);
FORCEPROP 1 LAST OFFPAGE TRUE
J 2
(-6700 5375);
DISPLAY 0.872340 (-6700 5375);
PAINT GREEN (-6700 5375);
DISPLAY INVISIBLE (-6700 5375);
FORCEPROP 1 LAST COMMENT_BODY TRUE
J 2
(-6475 5425);
DISPLAY 0.872340 (-6475 5425);
PAINT GREEN (-6475 5425);
DISPLAY INVISIBLE (-6475 5425);
FORCEPROP 2 LAST PATH I89
J 0
(-6200 5575);
DISPLAY 0.680851 (-6200 5575);
DISPLAY INVISIBLE (-6200 5575);
FORCEADD Q_RES..1
(-6600 1300);
FORCEPROP 1 LAST LOCATION R599
J 0
(-6850 1300);
DISPLAY 0.978723 (-6850 1300);
FORCEPROP 2 LAST SEC 1
J 0
(-6650 1500);
DISPLAY 0.680851 (-6650 1500);
PAINT MONO (-6650 1500);
DISPLAY INVISIBLE (-6650 1500);
FORCEPROP 1 LASTPIN (-6700 1300) $PN 1
J 0
(-6688 1312);
DISPLAY 0.787234 (-6688 1312);
PAINT MONO (-6688 1312);
FORCEPROP 1 LASTPIN (-6500 1300) $PN 2
J 0
(-6538 1312);
DISPLAY 0.787234 (-6538 1312);
PAINT MONO (-6538 1312);
FORCEPROP 1 LAST VALUE 0
J 2
(-6800 1425);
DISPLAY 0.787234 (-6800 1425);
FORCEPROP 1 LAST TOLERANCE 5%
J 0
(-6775 1425);
DISPLAY 0.787234 (-6775 1425);
FORCEPROP 1 LAST WATTAGE 1/20W
J 2
(-6800 1375);
DISPLAY 0.787234 (-6800 1375);
FORCEPROP 1 LAST PACK_TYPE 0201LF
J 0
(-6575 1375);
DISPLAY 0.787234 (-6575 1375);
FORCEPROP 1 LAST MATERIAL CHIP
J 0
(-6775 1375);
DISPLAY 0.787234 (-6775 1375);
FORCEPROP 2 LAST CDS_LIB pure_quanta
J 0
(-6600 1300);
DISPLAY INVISIBLE (-6600 1300);
FORCEPROP 0 LAST SEC_TYPE 0201LF
J 0
(-6650 1500);
DISPLAY 0.680851 (-6650 1500);
DISPLAY INVISIBLE (-6650 1500);
FORCEPROP 1 LAST PATH I9
J 0
(-6650 1450);
DISPLAY 0.978723 (-6650 1450);
PAINT WHITE (-6650 1450);
DISPLAY INVISIBLE (-6650 1450);
FORCEPROP 1 LAST PART_NUMBER CS00001JE10
J 0
(-6650 1425);
DISPLAY 0.808511 (-6650 1425);
DISPLAY INVISIBLE (-6650 1425);
FORCEADD Q_RES..2
(-7425 5100);
FORCEPROP 1 LAST LOCATION R726
J 0
(-7380 5225);
DISPLAY 0.787234 (-7380 5225);
FORCEPROP 0 LAST $SEC 1
J 0
(-7375 5275);
DISPLAY 0.680851 (-7375 5275);
PAINT MONO (-7375 5275);
DISPLAY INVISIBLE (-7375 5275);
FORCEPROP 0 LAST CDS_SEC 1
J 0
(-7375 5275);
DISPLAY 0.680851 (-7375 5275);
DISPLAY INVISIBLE (-7375 5275);
FORCEPROP 1 LASTPIN (-7425 5200) $PN 1
J 0
(-7420 5162);
DISPLAY 0.787234 (-7420 5162);
PAINT MONO (-7420 5162);
FORCEPROP 1 LASTPIN (-7425 5000) $PN 2
J 0
(-7420 5010);
DISPLAY 0.787234 (-7420 5010);
PAINT MONO (-7420 5010);
FORCEPROP 1 LAST TOLERANCE 5%
J 0
(-7380 5125);
DISPLAY 0.787234 (-7380 5125);
FORCEPROP 1 LAST PACK_TYPE 0201LF
J 0
(-7385 4925);
DISPLAY 0.787234 (-7385 4925);
FORCEPROP 1 LAST WATTAGE 1/20W
J 0
(-7385 5075);
DISPLAY 0.787234 (-7385 5075);
FORCEPROP 1 LAST VALUE 4.7K
J 0
(-7380 5175);
DISPLAY 0.787234 (-7380 5175);
FORCEPROP 1 LAST MATERIAL CHIP
J 0
(-7385 5025);
DISPLAY 0.787234 (-7385 5025);
FORCEPROP 2 LAST CDS_LIB pure_quanta
J 0
(-7425 5100);
DISPLAY INVISIBLE (-7425 5100);
FORCEPROP 1 LAST PATH I90
J 0
(-7375 5275);
DISPLAY 0.978723 (-7375 5275);
PAINT WHITE (-7375 5275);
DISPLAY INVISIBLE (-7375 5275);
FORCEPROP 1 LAST PART_NUMBER CS24701JE04
J 0
(-7385 4975);
DISPLAY 0.638298 (-7385 4975);
DISPLAY INVISIBLE (-7385 4975);
FORCEADD Q_RES..2
(-7425 6100);
FORCEPROP 1 LAST LOCATION R6725
J 0
(-7380 6225);
DISPLAY 0.787234 (-7380 6225);
FORCEPROP 0 LAST $SEC 1
J 0
(-7375 6275);
DISPLAY 0.680851 (-7375 6275);
PAINT MONO (-7375 6275);
DISPLAY INVISIBLE (-7375 6275);
FORCEPROP 0 LAST CDS_SEC 1
J 0
(-7375 6275);
DISPLAY 0.680851 (-7375 6275);
DISPLAY INVISIBLE (-7375 6275);
FORCEPROP 1 LASTPIN (-7425 6200) $PN 1
J 0
(-7420 6162);
DISPLAY 0.787234 (-7420 6162);
PAINT MONO (-7420 6162);
FORCEPROP 1 LASTPIN (-7425 6000) $PN 2
J 0
(-7420 6010);
DISPLAY 0.787234 (-7420 6010);
PAINT MONO (-7420 6010);
FORCEPROP 1 LAST TOLERANCE 5%
J 0
(-7380 6125);
DISPLAY 0.787234 (-7380 6125);
FORCEPROP 1 LAST VALUE 4.7K
J 0
(-7380 6175);
DISPLAY 0.787234 (-7380 6175);
FORCEPROP 1 LAST MATERIAL EMPTY
J 0
(-7385 6025);
DISPLAY 0.787234 (-7385 6025);
FORCEPROP 1 LAST WATTAGE 1/20W
J 0
(-7385 6075);
DISPLAY 0.787234 (-7385 6075);
FORCEPROP 1 LAST PACK_TYPE 0201LF
J 0
(-7375 5925);
DISPLAY 0.787234 (-7375 5925);
FORCEPROP 2 LAST CDS_LIB pure_quanta
J 0
(-7425 6100);
DISPLAY INVISIBLE (-7425 6100);
FORCEPROP 1 LAST PATH I91
J 0
(-7375 6275);
DISPLAY 0.978723 (-7375 6275);
PAINT WHITE (-7375 6275);
DISPLAY INVISIBLE (-7375 6275);
FORCEPROP 1 LAST PART_NUMBER CS24701JE04
J 0
(-7375 5975);
DISPLAY 0.638298 (-7375 5975);
DISPLAY INVISIBLE (-7375 5975);
FORCEADD OFFPAGE..1
R 2
(-2475 3200);
FORCEPROP 2 LAST $XR0 321 
J 0
(-2289 3200);
DISPLAY 0.638298 (-2289 3200);
PAINT MONO (-2289 3200);
FORCEPROP 2 LAST CDS_LIB standard
J 0
(-2475 3200);
DISPLAY INVISIBLE (-2475 3200);
FORCEPROP 1 LAST OFFPAGE TRUE
J 2
(-2800 3075);
DISPLAY 0.872340 (-2800 3075);
DISPLAY INVISIBLE (-2800 3075);
FORCEPROP 1 LAST COMMENT_BODY TRUE
J 2
(-2600 3100);
DISPLAY 0.872340 (-2600 3100);
PAINT GREEN (-2600 3100);
DISPLAY INVISIBLE (-2600 3100);
FORCEPROP 2 LAST PATH I92
J 0
(-2300 3275);
DISPLAY 0.680851 (-2300 3275);
DISPLAY INVISIBLE (-2300 3275);
FORCEADD UNIVERSAL_GND..1
R 1
(-2625 1800);
FORCEPROP 3 LASTPIN (-2675 1800) SIG_NAME GND\g
J 0
(-2665 1810);
DISPLAY 0.659574 (-2665 1810);
PAINT MONO (-2665 1810);
DISPLAY INVISIBLE (-2665 1810);
FORCEPROP 2 LAST CDS_LIB pure_quanta_power
J 0
(-2625 1800);
DISPLAY INVISIBLE (-2625 1800);
FORCEPROP 1 LAST HDL_POWER GND
R 1
J 1
(-2550 1825);
DISPLAY 0.872340 (-2550 1825);
PAINT GREEN (-2550 1825);
DISPLAY INVISIBLE (-2550 1825);
FORCEPROP 1 LAST PATH I93
R 1
J 0
(-2625 1875);
DISPLAY 0.872340 (-2625 1875);
PAINT AQUA (-2625 1875);
DISPLAY INVISIBLE (-2625 1875);
FORCEADD OFFPAGE..1
R 2
(-525 5550);
FORCEPROP 2 LAST $XR0 81 
J 0
(-339 5550);
DISPLAY 0.638298 (-339 5550);
PAINT MONO (-339 5550);
FORCEPROP 2 LAST $XR1 321 
J 0
(-249 5550);
DISPLAY 0.638298 (-249 5550);
PAINT MONO (-249 5550);
FORCEPROP 2 LAST CDS_LIB standard
J 0
(-525 5550);
DISPLAY INVISIBLE (-525 5550);
FORCEPROP 1 LAST OFFPAGE TRUE
J 2
(-850 5425);
DISPLAY 0.872340 (-850 5425);
PAINT GREEN (-850 5425);
DISPLAY INVISIBLE (-850 5425);
FORCEPROP 1 LAST COMMENT_BODY TRUE
J 2
(-650 5450);
DISPLAY 0.872340 (-650 5450);
PAINT GREEN (-650 5450);
DISPLAY INVISIBLE (-650 5450);
FORCEPROP 2 LAST PATH I94
J 0
(-350 5625);
DISPLAY 0.680851 (-350 5625);
DISPLAY INVISIBLE (-350 5625);
FORCEADD OFFPAGE..1
R 2
(-500 5700);
FORCEPROP 2 LAST $XR0 81 
J 0
(-314 5700);
DISPLAY 0.638298 (-314 5700);
PAINT MONO (-314 5700);
FORCEPROP 2 LAST $XR1 321 
J 0
(-224 5700);
DISPLAY 0.638298 (-224 5700);
PAINT MONO (-224 5700);
FORCEPROP 2 LAST CDS_LIB standard
J 0
(-500 5700);
DISPLAY INVISIBLE (-500 5700);
FORCEPROP 1 LAST OFFPAGE TRUE
J 2
(-825 5575);
DISPLAY 0.872340 (-825 5575);
PAINT GREEN (-825 5575);
DISPLAY INVISIBLE (-825 5575);
FORCEPROP 1 LAST COMMENT_BODY TRUE
J 2
(-625 5600);
DISPLAY 0.872340 (-625 5600);
PAINT GREEN (-625 5600);
DISPLAY INVISIBLE (-625 5600);
FORCEPROP 2 LAST PATH I95
J 0
(-325 5775);
DISPLAY 0.680851 (-325 5775);
DISPLAY INVISIBLE (-325 5775);
FORCEADD Q_RES..2
R 2
(-1475 5325);
FORCEPROP 1 LAST LOCATION R6721
J 2
(-1520 5450);
DISPLAY 0.638298 (-1520 5450);
FORCEPROP 0 LAST $SEC 1
J 0
(-1500 5500);
DISPLAY 0.680851 (-1500 5500);
PAINT MONO (-1500 5500);
DISPLAY INVISIBLE (-1500 5500);
FORCEPROP 0 LAST CDS_SEC 1
J 0
(-1500 5500);
DISPLAY 0.680851 (-1500 5500);
DISPLAY INVISIBLE (-1500 5500);
FORCEPROP 1 LASTPIN (-1475 5425) $PN 1
J 2
(-1480 5387);
DISPLAY 0.787234 (-1480 5387);
PAINT MONO (-1480 5387);
FORCEPROP 1 LASTPIN (-1475 5225) $PN 2
J 2
(-1480 5235);
DISPLAY 0.787234 (-1480 5235);
PAINT MONO (-1480 5235);
FORCEPROP 1 LAST TOLERANCE 1%
J 2
(-1520 5350);
DISPLAY 0.638298 (-1520 5350);
FORCEPROP 1 LAST MATERIAL CHIP
J 2
(-1515 5250);
DISPLAY 0.638298 (-1515 5250);
FORCEPROP 1 LAST PACK_TYPE 0201LF
J 2
(-1515 5150);
DISPLAY 0.638298 (-1515 5150);
FORCEPROP 1 LAST WATTAGE 1/20W
J 2
(-1515 5300);
DISPLAY 0.638298 (-1515 5300);
FORCEPROP 1 LAST VALUE 10K
J 2
(-1520 5400);
DISPLAY 0.638298 (-1520 5400);
FORCEPROP 2 LAST CDS_LIB pure_quanta
J 2
(-1475 5325);
DISPLAY INVISIBLE (-1475 5325);
FORCEPROP 1 LAST PATH I96
J 2
(-1525 5500);
DISPLAY 0.978723 (-1525 5500);
PAINT WHITE (-1525 5500);
DISPLAY INVISIBLE (-1525 5500);
FORCEPROP 1 LAST PART_NUMBER CS31001FE17
J 2
(-1515 5200);
DISPLAY 0.638298 (-1515 5200);
DISPLAY INVISIBLE (-1515 5200);
FORCEADD Q_RES..2
(-1300 5325);
FORCEPROP 1 LAST LOCATION R6720
J 0
(-1255 5450);
DISPLAY 0.638298 (-1255 5450);
FORCEPROP 0 LAST $SEC 1
J 0
(-1250 5500);
DISPLAY 0.680851 (-1250 5500);
PAINT MONO (-1250 5500);
DISPLAY INVISIBLE (-1250 5500);
FORCEPROP 0 LAST CDS_SEC 1
J 0
(-1250 5500);
DISPLAY 0.680851 (-1250 5500);
DISPLAY INVISIBLE (-1250 5500);
FORCEPROP 1 LASTPIN (-1300 5425) $PN 1
J 0
(-1295 5387);
DISPLAY 0.787234 (-1295 5387);
PAINT MONO (-1295 5387);
FORCEPROP 1 LASTPIN (-1300 5225) $PN 2
J 0
(-1295 5235);
DISPLAY 0.787234 (-1295 5235);
PAINT MONO (-1295 5235);
FORCEPROP 1 LAST VALUE 10K
J 0
(-1255 5400);
DISPLAY 0.638298 (-1255 5400);
FORCEPROP 1 LAST WATTAGE 1/20W
J 0
(-1260 5300);
DISPLAY 0.638298 (-1260 5300);
FORCEPROP 1 LAST MATERIAL CHIP
J 0
(-1260 5250);
DISPLAY 0.638298 (-1260 5250);
FORCEPROP 1 LAST PACK_TYPE 0201LF
J 0
(-1260 5150);
DISPLAY 0.638298 (-1260 5150);
FORCEPROP 1 LAST TOLERANCE 1%
J 0
(-1255 5350);
DISPLAY 0.638298 (-1255 5350);
FORCEPROP 2 LAST CDS_LIB pure_quanta
J 0
(-1300 5325);
DISPLAY INVISIBLE (-1300 5325);
FORCEPROP 1 LAST PATH I97
J 0
(-1250 5500);
DISPLAY 0.978723 (-1250 5500);
PAINT WHITE (-1250 5500);
DISPLAY INVISIBLE (-1250 5500);
FORCEPROP 1 LAST PART_NUMBER CS31001FE17
J 0
(-1260 5200);
DISPLAY 0.638298 (-1260 5200);
DISPLAY INVISIBLE (-1260 5200);
FORCEADD GND..1
(-1475 4950);
FORCEPROP 3 LASTPIN (-1475 5000) SIG_NAME GND\g
J 0
(-1465 5010);
DISPLAY 0.659574 (-1465 5010);
PAINT MONO (-1465 5010);
DISPLAY INVISIBLE (-1465 5010);
FORCEPROP 2 LAST BOM_COST MEM
J 0
(-1575 5025);
DISPLAY 0.808511 (-1575 5025);
DISPLAY INVISIBLE (-1575 5025);
FORCEPROP 1 LAST SIZE 1B
J 0
(-1400 4900);
DISPLAY 0.851064 (-1400 4900);
PAINT GREEN (-1400 4900);
DISPLAY INVISIBLE (-1400 4900);
FORCEPROP 2 LAST CDS_LIB pure_quanta_power
J 0
(-1475 4950);
DISPLAY INVISIBLE (-1475 4950);
FORCEPROP 1 LAST HDL_POWER GND
J 0
(-1475 5100);
DISPLAY 0.851064 (-1475 5100);
PAINT GREEN (-1475 5100);
DISPLAY INVISIBLE (-1475 5100);
FORCEPROP 1 LAST PATH I98
J 0
(-1400 4950);
DISPLAY 0.872340 (-1400 4950);
PAINT AQUA (-1400 4950);
DISPLAY INVISIBLE (-1400 4950);
FORCEADD GND..1
(-1300 4975);
FORCEPROP 3 LASTPIN (-1300 5025) SIG_NAME GND\g
J 0
(-1290 5035);
DISPLAY 0.659574 (-1290 5035);
PAINT MONO (-1290 5035);
DISPLAY INVISIBLE (-1290 5035);
FORCEPROP 2 LAST CDS_LIB pure_quanta_power
J 0
(-1300 4975);
DISPLAY INVISIBLE (-1300 4975);
FORCEPROP 2 LAST BOM_COST MEM
J 0
(-1400 5050);
DISPLAY 0.808511 (-1400 5050);
DISPLAY INVISIBLE (-1400 5050);
FORCEPROP 1 LAST SIZE 1B
J 0
(-1225 4925);
DISPLAY 0.851064 (-1225 4925);
PAINT GREEN (-1225 4925);
DISPLAY INVISIBLE (-1225 4925);
FORCEPROP 1 LAST HDL_POWER GND
J 0
(-1300 5125);
DISPLAY 0.851064 (-1300 5125);
PAINT GREEN (-1300 5125);
DISPLAY INVISIBLE (-1300 5125);
FORCEPROP 1 LAST PATH I99
J 0
(-1225 4975);
DISPLAY 0.872340 (-1225 4975);
PAINT AQUA (-1225 4975);
DISPLAY INVISIBLE (-1225 4975);
FORCEADD DNS..1
(-3425 5300);
PAINT RED (-3425 5300);
FORCEPROP 2 LAST CDS_LIB mstr_misc
J 0
(-3425 5300);
DISPLAY INVISIBLE (-3425 5300);
FORCEPROP 1 LAST COMMENT_BODY TRUE
R 1
J 0
(-3350 5075);
DISPLAY 0.872340 (-3350 5075);
PAINT GREEN (-3350 5075);
DISPLAY INVISIBLE (-3350 5075);
FORCEADD DNS..1
(-7325 6075);
PAINT RED (-7325 6075);
FORCEPROP 2 LAST CDS_LIB mstr_misc
J 0
(-7325 6075);
DISPLAY INVISIBLE (-7325 6075);
FORCEPROP 1 LAST COMMENT_BODY TRUE
R 1
J 0
(-7250 5850);
DISPLAY 0.872340 (-7250 5850);
PAINT GREEN (-7250 5850);
DISPLAY INVISIBLE (-7250 5850);
FORCEADD DNS..1
(-7650 6125);
PAINT RED (-7650 6125);
FORCEPROP 2 LAST CDS_LIB mstr_misc
J 0
(-7650 6125);
DISPLAY INVISIBLE (-7650 6125);
FORCEPROP 1 LAST COMMENT_BODY TRUE
R 1
J 0
(-7575 5900);
DISPLAY 0.872340 (-7575 5900);
PAINT GREEN (-7575 5900);
DISPLAY INVISIBLE (-7575 5900);
FORCEADD DNS..1
(-7925 6075);
PAINT RED (-7925 6075);
FORCEPROP 2 LAST CDS_LIB mstr_misc
J 0
(-7925 6075);
DISPLAY INVISIBLE (-7925 6075);
FORCEPROP 1 LAST COMMENT_BODY TRUE
R 1
J 0
(-7850 5850);
DISPLAY 0.872340 (-7850 5850);
PAINT GREEN (-7850 5850);
DISPLAY INVISIBLE (-7850 5850);
FORCEADD DNS..1
(-8225 6100);
PAINT RED (-8225 6100);
FORCEPROP 2 LAST CDS_LIB mstr_misc
J 0
(-8225 6100);
DISPLAY INVISIBLE (-8225 6100);
FORCEPROP 1 LAST COMMENT_BODY TRUE
R 1
J 0
(-8150 5875);
DISPLAY 0.872340 (-8150 5875);
PAINT GREEN (-8150 5875);
DISPLAY INVISIBLE (-8150 5875);
FORCEADD DNS..1
(-8825 6075);
PAINT RED (-8825 6075);
FORCEPROP 2 LAST CDS_LIB mstr_misc
J 0
(-8825 6075);
DISPLAY INVISIBLE (-8825 6075);
FORCEPROP 1 LAST COMMENT_BODY TRUE
R 1
J 0
(-8750 5850);
DISPLAY 0.872340 (-8750 5850);
PAINT GREEN (-8750 5850);
DISPLAY INVISIBLE (-8750 5850);
FORCEADD DNS..1
(-6075 850);
PAINT RED (-6075 850);
FORCEPROP 2 LAST CDS_LIB mstr_misc
J 0
(-6075 850);
DISPLAY INVISIBLE (-6075 850);
FORCEPROP 1 LAST COMMENT_BODY TRUE
R 1
J 0
(-6000 625);
DISPLAY 0.872340 (-6000 625);
PAINT GREEN (-6000 625);
DISPLAY INVISIBLE (-6000 625);
FORCEADD QUANTA_TITLE_BLOCK_C..1
(0 0);
FORCEPROP 0 LAST CDS_CON_LAST_MODIFIED Thu Sep 14 16:12:51 2023
J 0
(-1885 15);
DISPLAY INVISIBLE (-1885 15);
FORCEPROP 1 LAST CUSTOM_TXT_CDS <CON_LAST_MODIFIED>
J 0
(-1885 15);
DISPLAY 0.978723 (-1885 15);
FORCEPROP 2 LAST CUSTOM_TXT_CDS <XR_PAGE_TITLE>
J 0
(-7890 5250);
DISPLAY 0.638298 (-7890 5250);
PAINT PINK (-7890 5250);
DISPLAY INVISIBLE (-7890 5250);
FORCEPROP 1 LAST CUSTOM_TXT_CDS <NAME_2>
J 0
(-3175 50);
FORCEPROP 1 LAST CUSTOM_TXT_CDS <NAME_1>
J 0
(-3175 175);
FORCEPROP 1 LAST CUSTOM_TXT_CDS <Q_NUMBER>
J 0
(-1403 103);
DISPLAY 1.212766 (-1403 103);
FORCEPROP 1 LAST CUSTOM_TXT_CDS <Q_PROJ>
J 0
(-2382 102);
DISPLAY 1.212766 (-2382 102);
FORCEPROP 1 LAST CUSTOM_TXT_CDS <Q_REV>
J 0
(-184 103);
DISPLAY 1.212766 (-184 103);
FORCEPROP 1 LAST CUSTOM_TXT_CDS <CON_PAGE_NUM> OF <CON_TOTAL_PAGES>
J 0
(-446 18);
DISPLAY 0.978723 (-446 18);
FORCEPROP 1 LAST Q_TITLE RETIMER_CPU1_P0(5)
J 0
(-9366 26);
DISPLAY 2.446809 (-9366 26);
PAINT GREEN (-9366 26);
FORCEPROP 2 LAST CDS_XR_PAGE_TITLE CR-321 : @T6G_MB_LIB.T6G(SCH_1):PAGE321
J 0
(-7890 5250);
DISPLAY 0.638298 (-7890 5250);
PAINT PINK (-7890 5250);
DISPLAY INVISIBLE (-7890 5250);
FORCEPROP 2 LAST PAGE_BORDER TRUE
J 0
(-7890 5250);
DISPLAY 0.638298 (-7890 5250);
PAINT PINK (-7890 5250);
DISPLAY INVISIBLE (-7890 5250);
FORCEPROP 1 LAST CDS_LMAN_SYM_OUTLINE -9475,6775,100,-125
J 0
(0 0);
DISPLAY 0.468085 (0 0);
PAINT GREEN (0 0);
DISPLAY INVISIBLE (0 0);
FORCEPROP 2 LAST CDS_LIB pure_quanta
J 0
(0 0);
DISPLAY INVISIBLE (0 0);
FORCEPROP 1 LAST Q_DEPT BU9
J 1
(-3763 49);
DISPLAY 1.957447 (-3763 49);
PAINT GREEN (-3763 49);
DISPLAY INVISIBLE (-3763 49);
FORCEPROP 1 LAST COMMENT_BODY TRUE
J 0
(12 -13);
DISPLAY 0.978723 (12 -13);
PAINT GREEN (12 -13);
DISPLAY INVISIBLE (12 -13);
FORCEADD DNS..1
(-6425 825);
PAINT RED (-6425 825);
FORCEPROP 2 LAST CDS_LIB mstr_misc
J 0
(-6425 825);
DISPLAY INVISIBLE (-6425 825);
FORCEPROP 1 LAST COMMENT_BODY TRUE
R 1
J 0
(-6350 600);
DISPLAY 0.872340 (-6350 600);
PAINT GREEN (-6350 600);
DISPLAY INVISIBLE (-6350 600);
FORCEADD DNS..1
(-4950 5600);
PAINT RED (-4950 5600);
FORCEPROP 2 LAST CDS_LIB mstr_misc
J 0
(-4950 5600);
DISPLAY INVISIBLE (-4950 5600);
FORCEPROP 1 LAST COMMENT_BODY TRUE
R 1
J 0
(-4875 5375);
DISPLAY 0.872340 (-4875 5375);
PAINT GREEN (-4875 5375);
DISPLAY INVISIBLE (-4875 5375);
FORCEADD DNS..1
(-8925 4200);
PAINT RED (-8925 4200);
FORCEPROP 2 LAST CDS_LIB mstr_misc
J 0
(-8925 4200);
DISPLAY INVISIBLE (-8925 4200);
FORCEPROP 1 LAST COMMENT_BODY TRUE
R 1
J 0
(-8850 3975);
DISPLAY 0.872340 (-8850 3975);
PAINT GREEN (-8850 3975);
DISPLAY INVISIBLE (-8850 3975);
FORCEADD DNS..1
(-1475 6175);
PAINT RED (-1475 6175);
FORCEPROP 2 LAST CDS_LIB mstr_misc
J 0
(-1475 6175);
DISPLAY INVISIBLE (-1475 6175);
FORCEPROP 1 LAST COMMENT_BODY TRUE
R 1
J 0
(-1400 5950);
DISPLAY 0.872340 (-1400 5950);
PAINT GREEN (-1400 5950);
DISPLAY INVISIBLE (-1400 5950);
FORCEADD DNS..1
(-3125 6125);
PAINT RED (-3125 6125);
FORCEPROP 2 LAST CDS_LIB mstr_misc
J 0
(-3125 6125);
DISPLAY INVISIBLE (-3125 6125);
FORCEPROP 1 LAST COMMENT_BODY TRUE
R 1
J 0
(-3050 5900);
DISPLAY 0.872340 (-3050 5900);
PAINT GREEN (-3050 5900);
DISPLAY INVISIBLE (-3050 5900);
FORCEADD DNS..1
(-2775 6100);
PAINT RED (-2775 6100);
FORCEPROP 2 LAST CDS_LIB mstr_misc
J 0
(-2775 6100);
DISPLAY INVISIBLE (-2775 6100);
FORCEPROP 1 LAST COMMENT_BODY TRUE
R 1
J 0
(-2700 5875);
DISPLAY 0.872340 (-2700 5875);
PAINT GREEN (-2700 5875);
DISPLAY INVISIBLE (-2700 5875);
FORCEADD DNS..1
(-1450 4025);
PAINT RED (-1450 4025);
FORCEPROP 2 LAST CDS_LIB mstr_misc
J 0
(-1450 4025);
DISPLAY INVISIBLE (-1450 4025);
FORCEPROP 1 LAST COMMENT_BODY TRUE
R 1
J 0
(-1375 3800);
DISPLAY 0.872340 (-1375 3800);
PAINT GREEN (-1375 3800);
DISPLAY INVISIBLE (-1375 3800);
FORCEADD DNS..1
(-1150 1375);
PAINT RED (-1150 1375);
FORCEPROP 2 LAST CDS_LIB mstr_misc
J 0
(-1150 1375);
DISPLAY INVISIBLE (-1150 1375);
FORCEPROP 1 LAST COMMENT_BODY TRUE
R 1
J 0
(-1075 1150);
DISPLAY 0.872340 (-1075 1150);
PAINT GREEN (-1075 1150);
DISPLAY INVISIBLE (-1075 1150);
FORCEADD DNS..1
(-1450 1425);
PAINT RED (-1450 1425);
FORCEPROP 2 LAST CDS_LIB mstr_misc
J 0
(-1450 1425);
DISPLAY INVISIBLE (-1450 1425);
FORCEPROP 1 LAST COMMENT_BODY TRUE
R 1
J 0
(-1375 1200);
DISPLAY 0.872340 (-1375 1200);
PAINT GREEN (-1375 1200);
DISPLAY INVISIBLE (-1375 1200);
FORCEADD DNS..1
(-575 1400);
PAINT RED (-575 1400);
FORCEPROP 2 LAST CDS_LIB mstr_misc
J 0
(-575 1400);
DISPLAY INVISIBLE (-575 1400);
FORCEPROP 1 LAST COMMENT_BODY TRUE
R 1
J 0
(-500 1175);
DISPLAY 0.872340 (-500 1175);
PAINT GREEN (-500 1175);
DISPLAY INVISIBLE (-500 1175);
FORCEADD DNS..1
(-850 1400);
PAINT RED (-850 1400);
FORCEPROP 2 LAST CDS_LIB mstr_misc
J 0
(-850 1400);
DISPLAY INVISIBLE (-850 1400);
FORCEPROP 1 LAST COMMENT_BODY TRUE
R 1
J 0
(-775 1175);
DISPLAY 0.872340 (-775 1175);
PAINT GREEN (-775 1175);
DISPLAY INVISIBLE (-775 1175);
WIRE 16 -1 (-1475 6350)(-1475 6250);
WIRE 16 -1 (-2575 2400)(-2000 2400);
WIRE 16 -1 (-1525 3400)(-1525 3150);
WIRE 16 -1 (-2600 3350)(-2000 3350);
WIRE 16 -1 (-1525 4125)(-1525 4375);
WIRE 16 -1 (-650 650)(-650 500);
WIRE 16 -1 (-6150 725)(-6150 550);
WIRE 16 -1 (-6300 725)(-6300 550);
WIRE 16 -1 (-5025 6275)(-5025 6450);
WIRE 16 -1 (-5025 5550)(-5025 5350);
WIRE 16 -1 (-8975 3450)(-8975 3325);
WIRE 16 -1 (-8975 4325)(-8975 4500);
WIRE 16 -1 (-3775 1800)(-2675 1800);
WIRE 16 -1 (-1475 5225)(-1475 5000);
WIRE 16 -1 (-1300 5225)(-1300 5025);
WIRE 16 -1 (-6425 1750)(-7625 1750);
FORCEPROP 2 LAST SIG_NAME SMB_RT_CPU1_P0_ROM_MUX_1D_SCL
J 0
(-7535 1760);
DISPLAY 0.680851 (-7535 1760);
WIRE 16 -1 (-925 1475)(-925 1625);
WIRE 16 -1 (-925 1625)(-650 1625);
WIRE 16 -1 (-1200 1625)(-925 1625);
WIRE 16 -1 (-1475 1625)(-1200 1625);
WIRE 16 -1 (-1200 1475)(-1200 1625);
WIRE 16 -1 (-650 1500)(-650 1625);
WIRE 16 -1 (-650 1625)(-650 1650);
WIRE 16 -1 (-1475 1475)(-1475 1625);
WIRE 16 -1 (-8950 6400)(-8325 6400);
WIRE 16 -1 (-8950 6400)(-8950 6200);
WIRE 16 -1 (-8950 6450)(-8950 6400);
WIRE 16 -1 (-8025 6400)(-8325 6400);
WIRE 16 -1 (-8325 6400)(-8325 6200);
WIRE 16 -1 (-7725 6400)(-8025 6400);
WIRE 16 -1 (-8025 6400)(-8025 6150);
WIRE 16 -1 (-7725 6400)(-7425 6400);
WIRE 16 -1 (-7725 6400)(-7725 6175);
WIRE 16 -1 (-7425 6400)(-7425 6200);
WIRE 16 -1 (-7725 5025)(-7725 4825);
WIRE 16 -1 (-7725 4825)(-7425 4825);
WIRE 16 -1 (-7725 4825)(-8025 4825);
WIRE 16 -1 (-8025 5025)(-8025 4825);
WIRE 16 -1 (-8025 4825)(-8325 4825);
WIRE 16 -1 (-7425 5000)(-7425 4825);
WIRE 16 -1 (-7425 4825)(-7425 4700);
WIRE 16 -1 (-8325 5050)(-8325 4825);
WIRE 16 -1 (-8650 4825)(-8325 4825);
WIRE 16 -1 (-8650 5050)(-8650 4825);
WIRE 16 -1 (-8950 4825)(-8650 4825);
WIRE 16 -1 (-8950 5050)(-8950 4825);
WIRE 16 -1 (-2825 5225)(-2825 5050);
WIRE 16 -1 (-2825 5050)(-3175 5050);
WIRE 16 -1 (-3175 5225)(-3175 5050);
WIRE 16 -1 (-3175 5050)(-3475 5050);
WIRE 16 -1 (-3475 5225)(-3475 5050);
WIRE 16 -1 (-3475 5050)(-3475 4950);
WIRE 16 -1 (-3175 6425)(-2825 6425);
WIRE 16 -1 (-3175 6425)(-3175 6200);
WIRE 16 -1 (-3475 6425)(-3175 6425);
WIRE 16 -1 (-2825 6425)(-2825 6175);
WIRE 16 -1 (-3475 6200)(-3475 6425);
WIRE 16 -1 (-3475 6425)(-3475 6475);
WIRE 16 -1 (-5025 1750)(-6225 1750);
FORCEPROP 2 LAST SIG_NAME SMB_RT_CPU1_P0_ROM_MUX_1D_R_SCL
J 0
(-6185 1775);
DISPLAY 0.680851 (-6185 1775);
FORCEPROP 2 LASTPROP $XRERR UNIQUE?
J 0
(-6425 1775);
DISPLAY 0.638298 (-6425 1775);
PAINT MONO (-6425 1775);
DISPLAY INVISIBLE (-6425 1775);
WIRE 16 -1 (-5025 1650)(-6225 1650);
FORCEPROP 2 LAST SIG_NAME SMB_RT_CPU1_P0_ROM_MUX_1D_R_SDA
J 0
(-6185 1675);
DISPLAY 0.680851 (-6185 1675);
FORCEPROP 2 LASTPROP $XRERR UNIQUE?
J 0
(-6425 1675);
DISPLAY 0.638298 (-6425 1675);
PAINT MONO (-6425 1675);
DISPLAY INVISIBLE (-6425 1675);
WIRE 16 -1 (-6425 1650)(-7600 1650);
FORCEPROP 2 LAST SIG_NAME SMB_RT_CPU1_P0_ROM_MUX_1D_SDA
J 0
(-7535 1660);
DISPLAY 0.680851 (-7535 1660);
WIRE 16 -1 (-7850 4000)(-8975 4000);
FORCEPROP 2 LAST SIG_NAME RT_CPU1_P0_SCAN_MODE
J 0
(-8585 4010);
DISPLAY 0.680851 (-8585 4010);
WIRE 16 -1 (-8975 4125)(-8975 4000);
WIRE 16 -1 (-8975 4000)(-8975 3650);
WIRE 16 -1 (-2575 975)(-1475 975);
FORCEPROP 2 LAST SIG_NAME JTAG_TDI_RT_CPU1_P0
J 0
(-2410 985);
DISPLAY 0.680851 (-2410 985);
PAINT WHITE (-2410 985);
WIRE 16 -1 (-1475 1275)(-1475 975);
WIRE 16 -1 (-2575 1025)(-1200 1025);
FORCEPROP 2 LAST SIG_NAME JTAG_TMS_RT_CPU1_P0
J 0
(-2385 1035);
DISPLAY 0.680851 (-2385 1035);
PAINT WHITE (-2385 1035);
WIRE 16 -1 (-1200 1275)(-1200 1025);
WIRE 16 -1 (-2575 1075)(-925 1075);
FORCEPROP 2 LAST SIG_NAME JTAG_TDO_RT_CPU1_P0
J 0
(-2385 1085);
DISPLAY 0.680851 (-2385 1085);
PAINT WHITE (-2385 1085);
WIRE 16 -1 (-925 1275)(-925 1075);
WIRE 16 -1 (-2575 1125)(-650 1125);
FORCEPROP 2 LAST SIG_NAME JTAG_TCK_RT_CPU1_P0
J 0
(-2410 1135);
DISPLAY 0.680851 (-2410 1135);
PAINT WHITE (-2410 1135);
WIRE 16 -1 (-650 1300)(-650 1125);
WIRE 16 -1 (-650 1125)(-650 850);
WIRE 16 -1 (-3775 2300)(-2675 2300);
FORCEPROP 2 LAST SIG_NAME RST_RT_CPU1_P0_PERST_N
J 0
(-3610 2310);
DISPLAY 0.680851 (-3610 2310);
FORCEPROP 2 LASTPROP $XRERR UNIQUE?
J 0
(-3850 2310);
DISPLAY 0.638298 (-3850 2310);
PAINT MONO (-3850 2310);
DISPLAY INVISIBLE (-3850 2310);
WIRE 16 -1 (-3775 2400)(-2775 2400);
FORCEPROP 2 LAST SIG_NAME CLKREQ_RT_CPU1_P0_N
J 0
(-3510 2410);
DISPLAY 0.680851 (-3510 2410);
PAINT WHITE (-3510 2410);
FORCEPROP 2 LASTPROP $XRERR UNIQUE?
J 0
(-3750 2410);
DISPLAY 0.638298 (-3750 2410);
PAINT MONO (-3750 2410);
DISPLAY INVISIBLE (-3750 2410);
WIRE 16 -1 (-3775 2700)(-2425 2700);
FORCEPROP 2 LAST SIG_NAME RT_CPU1_P0_SCAN_MODE
J 0
(-3485 2710);
DISPLAY 0.680851 (-3485 2710);
WIRE 16 -1 (-3775 2800)(-2450 2800);
FORCEPROP 2 LAST SIG_NAME RXDET_BYP_RT_CPU1_P0
J 0
(-3460 2810);
DISPLAY 0.680851 (-3460 2810);
PAINT WHITE (-3460 2810);
WIRE 16 -1 (-3775 2900)(-2450 2900);
FORCEPROP 2 LAST SIG_NAME MODE_RT_CPU1_P0
J 0
(-3460 2910);
DISPLAY 0.680851 (-3460 2910);
WIRE 16 -1 (-3775 3450)(-2800 3450);
FORCEPROP 2 LAST SIG_NAME JTAG_TDI_RT_CPU1_P0
J 0
(-3610 3460);
DISPLAY 0.680851 (-3610 3460);
PAINT WHITE (-3610 3460);
WIRE 16 -1 (-3775 3550)(-2775 3550);
FORCEPROP 2 LAST SIG_NAME JTAG_TMS_RT_CPU1_P0
J 0
(-3585 3560);
DISPLAY 0.680851 (-3585 3560);
PAINT WHITE (-3585 3560);
WIRE 16 -1 (-3775 3650)(-2775 3650);
FORCEPROP 2 LAST SIG_NAME JTAG_TDO_RT_CPU1_P0
J 0
(-3585 3660);
DISPLAY 0.680851 (-3585 3660);
PAINT WHITE (-3585 3660);
WIRE 16 -1 (-3775 3750)(-2775 3750);
FORCEPROP 2 LAST SIG_NAME JTAG_TCK_RT_CPU1_P0
J 0
(-3610 3760);
DISPLAY 0.680851 (-3610 3760);
PAINT WHITE (-3610 3760);
WIRE 16 -1 (-3775 3350)(-2800 3350);
FORCEPROP 2 LAST SIG_NAME JTAG_TRST_RT_CPU1_P0_N
J 0
(-3610 3360);
DISPLAY 0.680851 (-3610 3360);
PAINT WHITE (-3610 3360);
FORCEPROP 2 LASTPROP $XRERR UNIQUE?
J 0
(-3850 3360);
DISPLAY 0.638298 (-3850 3360);
PAINT MONO (-3850 3360);
DISPLAY INVISIBLE (-3850 3360);
WIRE 16 -1 (-2475 2200)(-1100 2200);
FORCEPROP 2 LAST SIG_NAME RST_RT_CPU1_P0_RESET_R_N
J 0
(-1960 2210);
DISPLAY 0.680851 (-1960 2210);
WIRE 16 -1 (-2475 2300)(-1100 2300);
FORCEPROP 2 LAST SIG_NAME RST_RT_CPU1_P0_PERST_R_N
J 0
(-1935 2310);
DISPLAY 0.680851 (-1935 2310);
WIRE 16 -1 (-3775 3200)(-2525 3200);
FORCEPROP 2 LAST SIG_NAME JTAG_TEST_MODE_RT_CPU1_P0
J 0
(-3585 3210);
DISPLAY 0.680851 (-3585 3210);
WIRE 16 -1 (-725 3750)(-1525 3750);
FORCEPROP 2 LAST SIG_NAME RXDET_BYP_RT_CPU1_P0
J 0
(-1410 3760);
DISPLAY 0.680851 (-1410 3760);
PAINT WHITE (-1410 3760);
WIRE 16 -1 (-1525 3750)(-1525 3925);
WIRE 16 -1 (-1525 3600)(-1525 3750);
WIRE 16 -1 (-3775 2200)(-2675 2200);
FORCEPROP 2 LAST SIG_NAME RST_RT_CPU1_P0_RESET_N
J 0
(-3585 2210);
DISPLAY 0.680851 (-3585 2210);
FORCEPROP 2 LASTPROP $XRERR UNIQUE?
J 0
(-3825 2210);
DISPLAY 0.638298 (-3825 2210);
PAINT MONO (-3825 2210);
DISPLAY INVISIBLE (-3825 2210);
WIRE 16 -1 (-5025 3350)(-5975 3350);
FORCEPROP 2 LAST SIG_NAME GPIO3_RT_CPU1_P0
J 0
(-5835 3360);
DISPLAY 0.680851 (-5835 3360);
WIRE 16 -1 (-1475 6050)(-1475 5700);
WIRE 16 -1 (-550 5700)(-1475 5700);
FORCEPROP 2 LAST SIG_NAME RST_RT_CPU1_P0_RESET_R_N
J 0
(-1435 5735);
DISPLAY 0.680851 (-1435 5735);
WIRE 16 -1 (-1475 5425)(-1475 5700);
WIRE 16 -1 (-6700 1300)(-8000 1300);
FORCEPROP 2 LAST SIG_NAME CLK_100M_RETIMER_CPU1_P0_R_DP
J 0
(-7935 1310);
DISPLAY 0.680851 (-7935 1310);
WIRE 16 -1 (-6425 5725)(-8650 5725);
FORCEPROP 2 LAST SIG_NAME GPIO3_RT_CPU1_P0
J 0
(-7010 5735);
DISPLAY 0.680851 (-7010 5735);
WIRE 16 -1 (-8650 5725)(-8650 5250);
WIRE 16 -1 (-5025 2900)(-6250 2900);
FORCEPROP 2 LAST SIG_NAME SMB_RT_CPU1_P0_R2_SDA
J 0
(-6010 2910);
DISPLAY 0.680851 (-6010 2910);
FORCEPROP 2 LASTPROP $XRERR UNIQUE?
J 0
(-6250 2910);
DISPLAY 0.638298 (-6250 2910);
PAINT MONO (-6250 2910);
DISPLAY INVISIBLE (-6250 2910);
WIRE 16 -1 (-1975 5775)(-3475 5775);
FORCEPROP 2 LAST SIG_NAME RT_CPU1_P0_ADDR3
J 0
(-2760 5810);
DISPLAY 0.680851 (-2760 5810);
WIRE 16 -1 (-3475 6000)(-3475 5775);
WIRE 16 -1 (-3475 5775)(-3475 5425);
WIRE 16 -1 (-1975 5675)(-3175 5675);
FORCEPROP 2 LAST SIG_NAME RT_CPU1_P0_ADDR2
J 0
(-2760 5685);
DISPLAY 0.680851 (-2760 5685);
WIRE 16 -1 (-3175 5675)(-3175 6000);
WIRE 16 -1 (-3175 5425)(-3175 5675);
WIRE 16 -1 (-1975 5575)(-2825 5575);
FORCEPROP 2 LAST SIG_NAME RT_CPU1_P0_ADDR1
J 0
(-2760 5585);
DISPLAY 0.680851 (-2760 5585);
WIRE 16 -1 (-2825 5575)(-2825 5975);
WIRE 16 -1 (-2825 5425)(-2825 5575);
WIRE 16 -1 (-5025 6075)(-5025 5900);
WIRE 16 -1 (-4200 5900)(-5025 5900);
FORCEPROP 2 LAST SIG_NAME MODE_RT_CPU1_P0
J 0
(-4810 5910);
DISPLAY 0.680851 (-4810 5910);
WIRE 16 -1 (-5025 5750)(-5025 5900);
WIRE 16 -1 (-5025 1300)(-6150 1300);
FORCEPROP 2 LAST SIG_NAME CLK_100M_RETIMER_CPU1_P0_DP
J 0
(-6060 1310);
DISPLAY 0.680851 (-6060 1310);
FORCEPROP 2 LASTPROP $XRERR UNIQUE?
J 0
(-6300 1310);
DISPLAY 0.638298 (-6300 1310);
PAINT MONO (-6300 1310);
DISPLAY INVISIBLE (-6300 1310);
WIRE 16 -1 (-6150 1300)(-6500 1300);
WIRE 16 -1 (-6150 1300)(-6150 925);
WIRE 16 -1 (-5025 1150)(-6300 1150);
FORCEPROP 2 LAST SIG_NAME CLK_100M_RETIMER_CPU1_P0_DN
J 0
(-6060 1160);
DISPLAY 0.680851 (-6060 1160);
FORCEPROP 2 LASTPROP $XRERR UNIQUE?
J 0
(-6300 1160);
DISPLAY 0.638298 (-6300 1160);
PAINT MONO (-6300 1160);
DISPLAY INVISIBLE (-6300 1160);
WIRE 16 -1 (-6300 1150)(-6500 1150);
WIRE 16 -1 (-6300 1150)(-6300 925);
WIRE 16 -1 (-5025 2550)(-5925 2550);
FORCEPROP 2 LAST SIG_NAME RT_CPU1_P0_ADDR3
J 0
(-5785 2560);
DISPLAY 0.680851 (-5785 2560);
WIRE 16 -1 (-5025 3000)(-6250 3000);
FORCEPROP 2 LAST SIG_NAME SMB_RT_CPU1_P0_R2_SCL
J 0
(-6010 3010);
DISPLAY 0.680851 (-6010 3010);
FORCEPROP 2 LASTPROP $XRERR UNIQUE?
J 0
(-6250 3010);
DISPLAY 0.638298 (-6250 3010);
PAINT MONO (-6250 3010);
DISPLAY INVISIBLE (-6250 3010);
WIRE 16 -1 (-7725 5975)(-7725 5575);
WIRE 16 -1 (-6425 5575)(-7725 5575);
FORCEPROP 2 LAST SIG_NAME TEST2_RT_CPU1_P0
J 0
(-6985 5585);
DISPLAY 0.680851 (-6985 5585);
WIRE 16 -1 (-7725 5225)(-7725 5575);
WIRE 16 -1 (-6425 5500)(-7425 5500);
FORCEPROP 2 LAST SIG_NAME JTAG_TEST_MODE_RT_CPU1_P0
J 0
(-7235 5510);
DISPLAY 0.680851 (-7235 5510);
WIRE 16 -1 (-7425 6000)(-7425 5500);
WIRE 16 -1 (-7425 5500)(-7425 5200);
WIRE 16 -1 (-5025 2650)(-5925 2650);
FORCEPROP 2 LAST SIG_NAME RT_CPU1_P0_ADDR2
J 0
(-5785 2660);
DISPLAY 0.680851 (-5785 2660);
WIRE 16 -1 (-8950 6000)(-8950 5800);
WIRE 16 -1 (-6425 5800)(-8950 5800);
FORCEPROP 2 LAST SIG_NAME GPIO2_RT_CPU1_P0
J 0
(-6985 5810);
DISPLAY 0.680851 (-6985 5810);
WIRE 16 -1 (-8950 5250)(-8950 5800);
WIRE 16 -1 (-8325 6000)(-8325 5675);
WIRE 16 -1 (-6425 5675)(-8325 5675);
FORCEPROP 2 LAST SIG_NAME TEST0_RT_CPU1_P0
J 0
(-6985 5685);
DISPLAY 0.680851 (-6985 5685);
WIRE 16 -1 (-8325 5250)(-8325 5675);
WIRE 16 -1 (-1300 5425)(-1300 5550);
FORCEPROP 2 LAST SIG_NAME RST_RT_CPU1_P0_PERST_R_N
J 0
(-1335 5585);
DISPLAY 0.680851 (-1335 5585);
WIRE 16 -1 (-1300 5550)(-575 5550);
WIRE 16 -1 (-8025 5950)(-8025 5625);
WIRE 16 -1 (-6425 5625)(-8025 5625);
FORCEPROP 2 LAST SIG_NAME TEST1_RT_CPU1_P0
J 0
(-6985 5635);
DISPLAY 0.680851 (-6985 5635);
WIRE 16 -1 (-8025 5225)(-8025 5625);
WIRE 16 -1 (-6450 3000)(-7600 3000);
FORCEPROP 2 LAST SIG_NAME SMB_RT_CPU1_P0_R_SCL
J 0
(-7435 3010);
DISPLAY 0.680851 (-7435 3010);
WIRE 16 -1 (-5025 2050)(-6100 2050);
FORCEPROP 2 LAST SIG_NAME TEST2_RT_CPU1_P0
J 0
(-5785 2060);
DISPLAY 0.680851 (-5785 2060);
WIRE 16 -1 (-5025 2150)(-6100 2150);
FORCEPROP 2 LAST SIG_NAME TEST1_RT_CPU1_P0
J 0
(-5785 2160);
DISPLAY 0.680851 (-5785 2160);
WIRE 16 -1 (-5025 2250)(-6100 2250);
FORCEPROP 2 LAST SIG_NAME TEST0_RT_CPU1_P0
J 0
(-5785 2260);
DISPLAY 0.680851 (-5785 2260);
WIRE 16 -1 (-5025 2750)(-5925 2750);
FORCEPROP 2 LAST SIG_NAME RT_CPU1_P0_ADDR1
J 0
(-5785 2760);
DISPLAY 0.680851 (-5785 2760);
WIRE 16 -1 (-6450 2900)(-7600 2900);
FORCEPROP 2 LAST SIG_NAME SMB_RT_CPU1_P0_R_SDA
J 0
(-7435 2910);
DISPLAY 0.680851 (-7435 2910);
WIRE 16 -1 (-6700 1150)(-8000 1150);
FORCEPROP 2 LAST SIG_NAME CLK_100M_RETIMER_CPU1_P0_R_DN
J 0
(-7960 1160);
DISPLAY 0.680851 (-7960 1160);
WIRE 16 -1 (-5025 3450)(-5975 3450);
FORCEPROP 2 LAST SIG_NAME GPIO2_RT_CPU1_P0
J 0
(-5835 3460);
DISPLAY 0.680851 (-5835 3460);
DOT 1 (-650 1125);
DOT 1 (-650 1625);
DOT 1 (-925 1625);
DOT 1 (-1200 1625);
DOT 1 (-8975 4000);
DOT 1 (-1475 5700);
DOT 1 (-1525 3750);
DOT 1 (-7725 5575);
DOT 1 (-6300 1150);
DOT 1 (-7425 4825);
DOT 1 (-7725 4825);
DOT 1 (-7425 5500);
DOT 1 (-7725 6400);
DOT 1 (-8025 6400);
DOT 1 (-8025 5625);
DOT 1 (-8950 5800);
DOT 1 (-8025 4825);
DOT 1 (-8325 6400);
DOT 1 (-8325 4825);
DOT 1 (-8650 4825);
DOT 1 (-8950 6400);
DOT 1 (-6150 1300);
DOT 1 (-5025 5900);
DOT 1 (-3475 6425);
DOT 1 (-8325 5675);
DOT 1 (-3475 5050);
DOT 1 (-3175 6425);
DOT 1 (-3175 5050);
DOT 1 (-3175 5675);
DOT 1 (-2825 5575);
DOT 1 (-3475 5775);
FORCENOTE
CPU1 P0 RT ADDR: 0X48 (8-BIT) / 0X24 (7-BIT)
(-4275 4725) 0;
DISPLAY LEFT (-4275 4725);
DISPLAY 1.595745 (-4275 4725);
QUIT
